G04 ================== begin FILE IDENTIFICATION RECORD ==================*
G04 Layout Name:  12432-1.brd*
G04 Film Name:    NOTICE*
G04 File Format:  Gerber RS274X*
G04 File Origin:  Cadence Allegro 16.2-S037*
G04 Origin Date:  Wed Oct 17 10:59:56 2012*
G04 *
G04 Layer:  MANUFACTURING/THERMAL*
G04 *
G04 Offset:    (0.00 0.00)*
G04 Mirror:    No*
G04 Mode:      Positive*
G04 Rotation:  0*
G04 FullContactRelief:  No*
G04 UndefLineWidth:     6.00*
G04 ================== end FILE IDENTIFICATION RECORD ====================*
%FSLAX35Y35*MOIN*%
%IR0*IPPOS*OFA0.00000B0.00000*MIA0B0*SFA1.00000B1.00000*%
%ADD10C,.02*%
%ADD11C,.015*%
%ADD12C,.006*%
G75*
%LPD*%
G75*
G36*
G01X328317Y1154032D02*
G02X306771Y1175578I7501J29047D01*
G01X301631Y1175579D01*
G03X328318Y1148892I34187J7500D01*
G01X328317Y1154032D01*
G37*
G36*
G01X306771Y1190579D02*
G02X328317Y1212126I29047J-7500D01*
G01X328318Y1217266D01*
G03X301631Y1190578I7500J-34187D01*
G01X306771Y1190579D01*
G37*
G36*
G01X383188Y703960D02*
G02X355629Y741517I11812J37557D01*
G01Y757265D01*
X361534D01*
Y741517D01*
G03X383188Y710206I33464J0D01*
G01Y703960D01*
G37*
G36*
G01X355629Y796635D02*
Y812383D01*
G02X383188Y849940I39371J0D01*
G01Y843694D01*
G03X361534Y812383I11810J-31311D01*
G01Y796635D01*
X355629D01*
G37*
G36*
G01X364865Y1175578D02*
G02X343318Y1154032I-29047J7501D01*
G01X343317Y1148892D01*
G03X370005Y1175579I-7499J34187D01*
G01X364865Y1175578D01*
G37*
G36*
G01X343318Y1212126D02*
G02X364865Y1190579I-7500J-29047D01*
G01X370005Y1190578D01*
G03X343317Y1217266I-34187J-7499D01*
G01X343318Y1212126D01*
G37*
G36*
G01X406810Y703960D02*
Y710206D01*
G03X428464Y741517I-11810J31311D01*
G01Y757265D01*
X434369D01*
Y741517D01*
G02X406810Y703960I-39371J0D01*
G37*
G36*
G01X428464Y796635D02*
Y812383D01*
G03X406810Y843694I-33464J0D01*
G01Y849940D01*
G02X434369Y812383I-11812J-37557D01*
G01Y796635D01*
X428464D01*
G37*
G54D10*
G01X163299Y523450D02*
Y534075D01*
X163716Y535116D01*
X164549Y535742D01*
X165799Y535950D01*
X167049Y535533D01*
X167674Y534492D01*
G01X165174Y530950D02*
X161007D01*
G01X180049Y523450D02*
X178799Y523658D01*
X177549Y524491D01*
X176715Y525950D01*
X176299Y527617D01*
X176715Y529283D01*
X177549Y530742D01*
X178799Y531575D01*
X180049Y531783D01*
X181299Y531575D01*
X182549Y530742D01*
X183382Y529283D01*
X183591Y527617D01*
X183382Y525950D01*
X182549Y524491D01*
X181299Y523658D01*
X180049Y523450D01*
G01X195549D02*
Y535950D01*
G01X211049Y523450D02*
Y535950D01*
G01X226549Y523450D02*
X225299Y523658D01*
X224049Y524491D01*
X223215Y525950D01*
X222799Y527617D01*
X223215Y529283D01*
X224049Y530742D01*
X225299Y531575D01*
X226549Y531783D01*
X227799Y531575D01*
X229049Y530742D01*
X229882Y529283D01*
X230091Y527617D01*
X229882Y525950D01*
X229049Y524491D01*
X227799Y523658D01*
X226549Y523450D01*
G01X236840Y531783D02*
X239341Y523450D01*
X242049Y531783D01*
X244757Y523450D01*
X247258Y531783D01*
G01X270132Y520325D02*
X271591Y519492D01*
X273257Y519283D01*
X274716Y519492D01*
X275966Y520533D01*
X276799Y521992D01*
Y531783D01*
G01Y530117D02*
X275966Y530950D01*
X274716Y531575D01*
X273257Y531783D01*
X271591Y531367D01*
X270549Y530533D01*
X269715Y529075D01*
X269299Y527617D01*
X269507Y526366D01*
X270341Y524908D01*
X271591Y523867D01*
X273257Y523450D01*
X274507Y523658D01*
X275966Y524491D01*
X276799Y525325D01*
G01X285424Y529075D02*
X292091D01*
X291466Y530533D01*
X290424Y531367D01*
X288966Y531783D01*
X287507Y531575D01*
X286257Y530950D01*
X285424Y529492D01*
X285007Y528241D01*
Y526992D01*
X285424Y525742D01*
X286466Y524491D01*
X287716Y523658D01*
X289174Y523450D01*
X290632Y523867D01*
X292091Y525116D01*
G01X301132Y523450D02*
Y531783D01*
G01Y530117D02*
X302174Y530950D01*
X303216Y531575D01*
X304674Y531783D01*
X305716Y531575D01*
X306966Y530950D01*
G01X315799Y523450D02*
Y535950D01*
G01Y529700D02*
X316841Y530950D01*
X318091Y531575D01*
X319341Y531783D01*
X321216Y531367D01*
X322466Y530533D01*
X323299Y529075D01*
Y527408D01*
X322882Y525742D01*
X322049Y524491D01*
X320591Y523658D01*
X319341Y523450D01*
X318091Y523658D01*
X316841Y524283D01*
X315799Y525325D01*
G01X331924Y529075D02*
X338591D01*
X337966Y530533D01*
X336924Y531367D01*
X335466Y531783D01*
X334007Y531575D01*
X332757Y530950D01*
X331924Y529492D01*
X331507Y528241D01*
Y526992D01*
X331924Y525742D01*
X332966Y524491D01*
X334216Y523658D01*
X335674Y523450D01*
X337132Y523867D01*
X338591Y525116D01*
G01X347632Y523450D02*
Y531783D01*
G01Y530117D02*
X348674Y530950D01*
X349716Y531575D01*
X351174Y531783D01*
X352216Y531575D01*
X353466Y530950D01*
G01X385299Y535950D02*
Y523450D01*
G01Y525325D02*
X384466Y524283D01*
X383216Y523658D01*
X381757Y523450D01*
X380091Y523867D01*
X378841Y524908D01*
X378007Y526158D01*
X377799Y527617D01*
X378007Y529075D01*
X378841Y530325D01*
X380091Y531367D01*
X381757Y531783D01*
X383216Y531575D01*
X384257Y531158D01*
X385299Y530325D01*
G01X393924Y529075D02*
X400591D01*
X399966Y530533D01*
X398924Y531367D01*
X397466Y531783D01*
X396007Y531575D01*
X394757Y530950D01*
X393924Y529492D01*
X393507Y528241D01*
Y526992D01*
X393924Y525742D01*
X394966Y524491D01*
X396216Y523658D01*
X397674Y523450D01*
X399132Y523867D01*
X400591Y525116D01*
G01X409424Y524908D02*
X410466Y524075D01*
X411924Y523450D01*
X413174D01*
X414424Y523867D01*
X415257Y524491D01*
X415674Y525325D01*
X415466Y526575D01*
X414632Y527200D01*
X410882Y528450D01*
X410049Y529908D01*
X410466Y530950D01*
X411299Y531575D01*
X412549Y531783D01*
X413799Y531575D01*
X415049Y530950D01*
G01X428049Y531783D02*
Y523450D01*
G01Y535116D02*
X427632Y535325D01*
Y535742D01*
X428049Y535950D01*
X428466Y535742D01*
Y535325D01*
X428049Y535116D01*
G01X440632Y520325D02*
X442091Y519492D01*
X443757Y519283D01*
X445216Y519492D01*
X446466Y520533D01*
X447299Y521992D01*
Y531783D01*
G01Y530117D02*
X446466Y530950D01*
X445216Y531575D01*
X443757Y531783D01*
X442091Y531367D01*
X441049Y530533D01*
X440215Y529075D01*
X439799Y527617D01*
X440007Y526366D01*
X440841Y524908D01*
X442091Y523867D01*
X443757Y523450D01*
X445007Y523658D01*
X446466Y524491D01*
X447299Y525325D01*
G01X455507Y523450D02*
Y531783D01*
G01Y529700D02*
X456341Y530742D01*
X457591Y531575D01*
X459257Y531783D01*
X460716Y531575D01*
X461966Y530742D01*
X462591Y529283D01*
Y523450D01*
G01X160591Y545150D02*
Y557650D01*
X168507D01*
G01X165591Y551608D02*
X160591D01*
G01X180049Y545150D02*
X178799Y545358D01*
X177549Y546191D01*
X176715Y547650D01*
X176299Y549317D01*
X176715Y550983D01*
X177549Y552442D01*
X178799Y553275D01*
X180049Y553483D01*
X181299Y553275D01*
X182549Y552442D01*
X183382Y550983D01*
X183591Y549317D01*
X183382Y547650D01*
X182549Y546191D01*
X181299Y545358D01*
X180049Y545150D01*
G01X192632D02*
Y553483D01*
G01Y551817D02*
X193674Y552650D01*
X194716Y553275D01*
X196174Y553483D01*
X197216Y553275D01*
X198466Y552650D01*
G01X222591Y555567D02*
X223841Y556816D01*
X225299Y557442D01*
X226966Y557650D01*
X229049Y557233D01*
X230507Y556192D01*
X230924Y554942D01*
X230716Y553691D01*
X229882Y552650D01*
X225716Y550567D01*
X223841Y549108D01*
X222591Y547025D01*
X222174Y545150D01*
X230924D01*
G01X241632D02*
X242049Y547858D01*
X242674Y550150D01*
X243507Y552233D01*
X244549Y554525D01*
X246216Y557650D01*
X237882D01*
G01X260049Y545150D02*
Y557650D01*
X252340Y548692D01*
X262758D01*
G01X268674Y545150D02*
X277424Y557650D01*
G01X268674D02*
X277424Y545150D01*
G01X301132Y542025D02*
X302591Y541192D01*
X304257Y540983D01*
X305716Y541192D01*
X306966Y542233D01*
X307799Y543692D01*
Y553483D01*
G01Y551817D02*
X306966Y552650D01*
X305716Y553275D01*
X304257Y553483D01*
X302591Y553067D01*
X301549Y552233D01*
X300715Y550775D01*
X300299Y549317D01*
X300507Y548066D01*
X301341Y546608D01*
X302591Y545567D01*
X304257Y545150D01*
X305507Y545358D01*
X306966Y546191D01*
X307799Y547025D01*
G01X316424Y550775D02*
X323091D01*
X322466Y552233D01*
X321424Y553067D01*
X319966Y553483D01*
X318507Y553275D01*
X317257Y552650D01*
X316424Y551192D01*
X316007Y549941D01*
Y548692D01*
X316424Y547442D01*
X317466Y546191D01*
X318716Y545358D01*
X320174Y545150D01*
X321632Y545567D01*
X323091Y546816D01*
G01X332132Y545150D02*
Y553483D01*
G01Y551817D02*
X333174Y552650D01*
X334216Y553275D01*
X335674Y553483D01*
X336716Y553275D01*
X337966Y552650D01*
G01X346799Y545150D02*
Y557650D01*
G01Y551400D02*
X347841Y552650D01*
X349091Y553275D01*
X350341Y553483D01*
X352216Y553067D01*
X353466Y552233D01*
X354299Y550775D01*
Y549108D01*
X353882Y547442D01*
X353049Y546191D01*
X351591Y545358D01*
X350341Y545150D01*
X349091Y545358D01*
X347841Y545983D01*
X346799Y547025D01*
G01X362924Y550775D02*
X369591D01*
X368966Y552233D01*
X367924Y553067D01*
X366466Y553483D01*
X365007Y553275D01*
X363757Y552650D01*
X362924Y551192D01*
X362507Y549941D01*
Y548692D01*
X362924Y547442D01*
X363966Y546191D01*
X365216Y545358D01*
X366674Y545150D01*
X368132Y545567D01*
X369591Y546816D01*
G01X378632Y545150D02*
Y553483D01*
G01Y551817D02*
X379674Y552650D01*
X380716Y553275D01*
X382174Y553483D01*
X383216Y553275D01*
X384466Y552650D01*
G01X411299Y545150D02*
Y555775D01*
X411716Y556816D01*
X412549Y557442D01*
X413799Y557650D01*
X415049Y557233D01*
X415674Y556192D01*
G01X413174Y552650D02*
X409007D01*
G01X428049Y545150D02*
X426799Y545358D01*
X425549Y546191D01*
X424715Y547650D01*
X424299Y549317D01*
X424715Y550983D01*
X425549Y552442D01*
X426799Y553275D01*
X428049Y553483D01*
X429299Y553275D01*
X430549Y552442D01*
X431382Y550983D01*
X431591Y549317D01*
X431382Y547650D01*
X430549Y546191D01*
X429299Y545358D01*
X428049Y545150D01*
G01X440632D02*
Y553483D01*
G01Y551817D02*
X441674Y552650D01*
X442716Y553275D01*
X444174Y553483D01*
X445216Y553275D01*
X446466Y552650D01*
G01X452799Y545150D02*
Y553483D01*
G01Y551192D02*
X453424Y552233D01*
X454466Y553067D01*
X455924Y553483D01*
X457382Y553067D01*
X458424Y552233D01*
X459049Y551192D01*
Y545150D01*
G01Y551192D02*
X459674Y552233D01*
X460716Y553067D01*
X462174Y553483D01*
X463632Y553067D01*
X464674Y552233D01*
X465299Y550983D01*
Y545150D01*
G01X478299D02*
Y553483D01*
G01Y552025D02*
X477466Y552858D01*
X476216Y553275D01*
X474757Y553483D01*
X473299Y553067D01*
X472049Y552233D01*
X471215Y550983D01*
X470799Y549317D01*
X471215Y547650D01*
X472049Y546400D01*
X473299Y545567D01*
X474757Y545150D01*
X476216Y545358D01*
X477466Y545983D01*
X478299Y546816D01*
G01X490049Y557650D02*
Y545150D01*
G01X487132Y553483D02*
X492966D01*
G01X521049Y557650D02*
Y545150D01*
G01X518132Y553483D02*
X523966D01*
G01X533007Y545150D02*
Y557650D01*
G01Y551608D02*
X534049Y552650D01*
X535091Y553275D01*
X536757Y553483D01*
X538007Y553275D01*
X539466Y552442D01*
X540091Y551192D01*
Y545150D01*
G01X548924Y550775D02*
X555591D01*
X554966Y552233D01*
X553924Y553067D01*
X552466Y553483D01*
X551007Y553275D01*
X549757Y552650D01*
X548924Y551192D01*
X548507Y549941D01*
Y548692D01*
X548924Y547442D01*
X549966Y546191D01*
X551216Y545358D01*
X552674Y545150D01*
X554132Y545567D01*
X555591Y546816D01*
G01X564632Y545150D02*
Y553483D01*
G01Y551817D02*
X565674Y552650D01*
X566716Y553275D01*
X568174Y553483D01*
X569216Y553275D01*
X570466Y552650D01*
G01X576799Y545150D02*
Y553483D01*
G01Y551192D02*
X577424Y552233D01*
X578466Y553067D01*
X579924Y553483D01*
X581382Y553067D01*
X582424Y552233D01*
X583049Y551192D01*
Y545150D01*
G01Y551192D02*
X583674Y552233D01*
X584716Y553067D01*
X586174Y553483D01*
X587632Y553067D01*
X588674Y552233D01*
X589299Y550983D01*
Y545150D01*
G01X602299D02*
Y553483D01*
G01Y552025D02*
X601466Y552858D01*
X600216Y553275D01*
X598757Y553483D01*
X597299Y553067D01*
X596049Y552233D01*
X595215Y550983D01*
X594799Y549317D01*
X595215Y547650D01*
X596049Y546400D01*
X597299Y545567D01*
X598757Y545150D01*
X600216Y545358D01*
X601466Y545983D01*
X602299Y546816D01*
G01X614049Y545150D02*
Y557650D01*
G01X642132Y545150D02*
Y553483D01*
G01Y551817D02*
X643174Y552650D01*
X644216Y553275D01*
X645674Y553483D01*
X646716Y553275D01*
X647966Y552650D01*
G01X657424Y550775D02*
X664091D01*
X663466Y552233D01*
X662424Y553067D01*
X660966Y553483D01*
X659507Y553275D01*
X658257Y552650D01*
X657424Y551192D01*
X657007Y549941D01*
Y548692D01*
X657424Y547442D01*
X658466Y546191D01*
X659716Y545358D01*
X661174Y545150D01*
X662632Y545567D01*
X664091Y546816D01*
G01X676049Y545150D02*
Y557650D01*
G01X691549Y553483D02*
Y545150D01*
G01Y556816D02*
X691132Y557025D01*
Y557442D01*
X691549Y557650D01*
X691966Y557442D01*
Y557025D01*
X691549Y556816D01*
G01X703924Y550775D02*
X710591D01*
X709966Y552233D01*
X708924Y553067D01*
X707466Y553483D01*
X706007Y553275D01*
X704757Y552650D01*
X703924Y551192D01*
X703507Y549941D01*
Y548692D01*
X703924Y547442D01*
X704966Y546191D01*
X706216Y545358D01*
X707674Y545150D01*
X709132Y545567D01*
X710591Y546816D01*
G01X721299Y545150D02*
Y555775D01*
X721716Y556816D01*
X722549Y557442D01*
X723799Y557650D01*
X725049Y557233D01*
X725674Y556192D01*
G01X723174Y552650D02*
X719007D01*
G01X172899Y977350D02*
Y987975D01*
X173316Y989016D01*
X174149Y989642D01*
X175399Y989850D01*
X176649Y989433D01*
X177274Y988392D01*
G01X174774Y984850D02*
X170607D01*
G01X189649Y977350D02*
X188399Y977558D01*
X187149Y978391D01*
X186315Y979850D01*
X185899Y981517D01*
X186315Y983183D01*
X187149Y984642D01*
X188399Y985475D01*
X189649Y985683D01*
X190899Y985475D01*
X192149Y984642D01*
X192982Y983183D01*
X193191Y981517D01*
X192982Y979850D01*
X192149Y978391D01*
X190899Y977558D01*
X189649Y977350D01*
G01X205149D02*
Y989850D01*
G01X220649Y977350D02*
Y989850D01*
G01X236149Y977350D02*
X234899Y977558D01*
X233649Y978391D01*
X232815Y979850D01*
X232399Y981517D01*
X232815Y983183D01*
X233649Y984642D01*
X234899Y985475D01*
X236149Y985683D01*
X237399Y985475D01*
X238649Y984642D01*
X239482Y983183D01*
X239691Y981517D01*
X239482Y979850D01*
X238649Y978391D01*
X237399Y977558D01*
X236149Y977350D01*
G01X246440Y985683D02*
X248941Y977350D01*
X251649Y985683D01*
X254357Y977350D01*
X256858Y985683D01*
G01X279732Y974225D02*
X281191Y973392D01*
X282857Y973183D01*
X284316Y973392D01*
X285566Y974433D01*
X286399Y975892D01*
Y985683D01*
G01Y984017D02*
X285566Y984850D01*
X284316Y985475D01*
X282857Y985683D01*
X281191Y985267D01*
X280149Y984433D01*
X279315Y982975D01*
X278899Y981517D01*
X279107Y980266D01*
X279941Y978808D01*
X281191Y977767D01*
X282857Y977350D01*
X284107Y977558D01*
X285566Y978391D01*
X286399Y979225D01*
G01X295024Y982975D02*
X301691D01*
X301066Y984433D01*
X300024Y985267D01*
X298566Y985683D01*
X297107Y985475D01*
X295857Y984850D01*
X295024Y983392D01*
X294607Y982141D01*
Y980892D01*
X295024Y979642D01*
X296066Y978391D01*
X297316Y977558D01*
X298774Y977350D01*
X300232Y977767D01*
X301691Y979016D01*
G01X310732Y977350D02*
Y985683D01*
G01Y984017D02*
X311774Y984850D01*
X312816Y985475D01*
X314274Y985683D01*
X315316Y985475D01*
X316566Y984850D01*
G01X325399Y977350D02*
Y989850D01*
G01Y983600D02*
X326441Y984850D01*
X327691Y985475D01*
X328941Y985683D01*
X330816Y985267D01*
X332066Y984433D01*
X332899Y982975D01*
Y981308D01*
X332482Y979642D01*
X331649Y978391D01*
X330191Y977558D01*
X328941Y977350D01*
X327691Y977558D01*
X326441Y978183D01*
X325399Y979225D01*
G01X341524Y982975D02*
X348191D01*
X347566Y984433D01*
X346524Y985267D01*
X345066Y985683D01*
X343607Y985475D01*
X342357Y984850D01*
X341524Y983392D01*
X341107Y982141D01*
Y980892D01*
X341524Y979642D01*
X342566Y978391D01*
X343816Y977558D01*
X345274Y977350D01*
X346732Y977767D01*
X348191Y979016D01*
G01X357232Y977350D02*
Y985683D01*
G01Y984017D02*
X358274Y984850D01*
X359316Y985475D01*
X360774Y985683D01*
X361816Y985475D01*
X363066Y984850D01*
G01X394899Y989850D02*
Y977350D01*
G01Y979225D02*
X394066Y978183D01*
X392816Y977558D01*
X391357Y977350D01*
X389691Y977767D01*
X388441Y978808D01*
X387607Y980058D01*
X387399Y981517D01*
X387607Y982975D01*
X388441Y984225D01*
X389691Y985267D01*
X391357Y985683D01*
X392816Y985475D01*
X393857Y985058D01*
X394899Y984225D01*
G01X403524Y982975D02*
X410191D01*
X409566Y984433D01*
X408524Y985267D01*
X407066Y985683D01*
X405607Y985475D01*
X404357Y984850D01*
X403524Y983392D01*
X403107Y982141D01*
Y980892D01*
X403524Y979642D01*
X404566Y978391D01*
X405816Y977558D01*
X407274Y977350D01*
X408732Y977767D01*
X410191Y979016D01*
G01X419024Y978808D02*
X420066Y977975D01*
X421524Y977350D01*
X422774D01*
X424024Y977767D01*
X424857Y978391D01*
X425274Y979225D01*
X425066Y980475D01*
X424232Y981100D01*
X420482Y982350D01*
X419649Y983808D01*
X420066Y984850D01*
X420899Y985475D01*
X422149Y985683D01*
X423399Y985475D01*
X424649Y984850D01*
G01X437649Y985683D02*
Y977350D01*
G01Y989016D02*
X437232Y989225D01*
Y989642D01*
X437649Y989850D01*
X438066Y989642D01*
Y989225D01*
X437649Y989016D01*
G01X450232Y974225D02*
X451691Y973392D01*
X453357Y973183D01*
X454816Y973392D01*
X456066Y974433D01*
X456899Y975892D01*
Y985683D01*
G01Y984017D02*
X456066Y984850D01*
X454816Y985475D01*
X453357Y985683D01*
X451691Y985267D01*
X450649Y984433D01*
X449815Y982975D01*
X449399Y981517D01*
X449607Y980266D01*
X450441Y978808D01*
X451691Y977767D01*
X453357Y977350D01*
X454607Y977558D01*
X456066Y978391D01*
X456899Y979225D01*
G01X465107Y977350D02*
Y985683D01*
G01Y983600D02*
X465941Y984642D01*
X467191Y985475D01*
X468857Y985683D01*
X470316Y985475D01*
X471566Y984642D01*
X472191Y983183D01*
Y977350D01*
G01X170191Y999050D02*
Y1011550D01*
X178107D01*
G01X175191Y1005508D02*
X170191D01*
G01X189649Y999050D02*
X188399Y999258D01*
X187149Y1000091D01*
X186315Y1001550D01*
X185899Y1003217D01*
X186315Y1004883D01*
X187149Y1006342D01*
X188399Y1007175D01*
X189649Y1007383D01*
X190899Y1007175D01*
X192149Y1006342D01*
X192982Y1004883D01*
X193191Y1003217D01*
X192982Y1001550D01*
X192149Y1000091D01*
X190899Y999258D01*
X189649Y999050D01*
G01X202232D02*
Y1007383D01*
G01Y1005717D02*
X203274Y1006550D01*
X204316Y1007175D01*
X205774Y1007383D01*
X206816Y1007175D01*
X208066Y1006550D01*
G01X232191Y1009467D02*
X233441Y1010716D01*
X234899Y1011342D01*
X236566Y1011550D01*
X238649Y1011133D01*
X240107Y1010092D01*
X240524Y1008842D01*
X240316Y1007591D01*
X239482Y1006550D01*
X235316Y1004467D01*
X233441Y1003008D01*
X232191Y1000925D01*
X231774Y999050D01*
X240524D01*
G01X251232D02*
X251649Y1001758D01*
X252274Y1004050D01*
X253107Y1006133D01*
X254149Y1008425D01*
X255816Y1011550D01*
X247482D01*
G01X269649Y999050D02*
Y1011550D01*
X261940Y1002592D01*
X272358D01*
G01X278274Y999050D02*
X287024Y1011550D01*
G01X278274D02*
X287024Y999050D01*
G01X310732Y995925D02*
X312191Y995092D01*
X313857Y994883D01*
X315316Y995092D01*
X316566Y996133D01*
X317399Y997592D01*
Y1007383D01*
G01Y1005717D02*
X316566Y1006550D01*
X315316Y1007175D01*
X313857Y1007383D01*
X312191Y1006967D01*
X311149Y1006133D01*
X310315Y1004675D01*
X309899Y1003217D01*
X310107Y1001966D01*
X310941Y1000508D01*
X312191Y999467D01*
X313857Y999050D01*
X315107Y999258D01*
X316566Y1000091D01*
X317399Y1000925D01*
G01X326024Y1004675D02*
X332691D01*
X332066Y1006133D01*
X331024Y1006967D01*
X329566Y1007383D01*
X328107Y1007175D01*
X326857Y1006550D01*
X326024Y1005092D01*
X325607Y1003841D01*
Y1002592D01*
X326024Y1001342D01*
X327066Y1000091D01*
X328316Y999258D01*
X329774Y999050D01*
X331232Y999467D01*
X332691Y1000716D01*
G01X341732Y999050D02*
Y1007383D01*
G01Y1005717D02*
X342774Y1006550D01*
X343816Y1007175D01*
X345274Y1007383D01*
X346316Y1007175D01*
X347566Y1006550D01*
G01X356399Y999050D02*
Y1011550D01*
G01Y1005300D02*
X357441Y1006550D01*
X358691Y1007175D01*
X359941Y1007383D01*
X361816Y1006967D01*
X363066Y1006133D01*
X363899Y1004675D01*
Y1003008D01*
X363482Y1001342D01*
X362649Y1000091D01*
X361191Y999258D01*
X359941Y999050D01*
X358691Y999258D01*
X357441Y999883D01*
X356399Y1000925D01*
G01X372524Y1004675D02*
X379191D01*
X378566Y1006133D01*
X377524Y1006967D01*
X376066Y1007383D01*
X374607Y1007175D01*
X373357Y1006550D01*
X372524Y1005092D01*
X372107Y1003841D01*
Y1002592D01*
X372524Y1001342D01*
X373566Y1000091D01*
X374816Y999258D01*
X376274Y999050D01*
X377732Y999467D01*
X379191Y1000716D01*
G01X388232Y999050D02*
Y1007383D01*
G01Y1005717D02*
X389274Y1006550D01*
X390316Y1007175D01*
X391774Y1007383D01*
X392816Y1007175D01*
X394066Y1006550D01*
G01X420899Y999050D02*
Y1009675D01*
X421316Y1010716D01*
X422149Y1011342D01*
X423399Y1011550D01*
X424649Y1011133D01*
X425274Y1010092D01*
G01X422774Y1006550D02*
X418607D01*
G01X437649Y999050D02*
X436399Y999258D01*
X435149Y1000091D01*
X434315Y1001550D01*
X433899Y1003217D01*
X434315Y1004883D01*
X435149Y1006342D01*
X436399Y1007175D01*
X437649Y1007383D01*
X438899Y1007175D01*
X440149Y1006342D01*
X440982Y1004883D01*
X441191Y1003217D01*
X440982Y1001550D01*
X440149Y1000091D01*
X438899Y999258D01*
X437649Y999050D01*
G01X450232D02*
Y1007383D01*
G01Y1005717D02*
X451274Y1006550D01*
X452316Y1007175D01*
X453774Y1007383D01*
X454816Y1007175D01*
X456066Y1006550D01*
G01X462399Y999050D02*
Y1007383D01*
G01Y1005092D02*
X463024Y1006133D01*
X464066Y1006967D01*
X465524Y1007383D01*
X466982Y1006967D01*
X468024Y1006133D01*
X468649Y1005092D01*
Y999050D01*
G01Y1005092D02*
X469274Y1006133D01*
X470316Y1006967D01*
X471774Y1007383D01*
X473232Y1006967D01*
X474274Y1006133D01*
X474899Y1004883D01*
Y999050D01*
G01X487899D02*
Y1007383D01*
G01Y1005925D02*
X487066Y1006758D01*
X485816Y1007175D01*
X484357Y1007383D01*
X482899Y1006967D01*
X481649Y1006133D01*
X480815Y1004883D01*
X480399Y1003217D01*
X480815Y1001550D01*
X481649Y1000300D01*
X482899Y999467D01*
X484357Y999050D01*
X485816Y999258D01*
X487066Y999883D01*
X487899Y1000716D01*
G01X499649Y1011550D02*
Y999050D01*
G01X496732Y1007383D02*
X502566D01*
G01X530649Y1011550D02*
Y999050D01*
G01X527732Y1007383D02*
X533566D01*
G01X542607Y999050D02*
Y1011550D01*
G01Y1005508D02*
X543649Y1006550D01*
X544691Y1007175D01*
X546357Y1007383D01*
X547607Y1007175D01*
X549066Y1006342D01*
X549691Y1005092D01*
Y999050D01*
G01X558524Y1004675D02*
X565191D01*
X564566Y1006133D01*
X563524Y1006967D01*
X562066Y1007383D01*
X560607Y1007175D01*
X559357Y1006550D01*
X558524Y1005092D01*
X558107Y1003841D01*
Y1002592D01*
X558524Y1001342D01*
X559566Y1000091D01*
X560816Y999258D01*
X562274Y999050D01*
X563732Y999467D01*
X565191Y1000716D01*
G01X574232Y999050D02*
Y1007383D01*
G01Y1005717D02*
X575274Y1006550D01*
X576316Y1007175D01*
X577774Y1007383D01*
X578816Y1007175D01*
X580066Y1006550D01*
G01X586399Y999050D02*
Y1007383D01*
G01Y1005092D02*
X587024Y1006133D01*
X588066Y1006967D01*
X589524Y1007383D01*
X590982Y1006967D01*
X592024Y1006133D01*
X592649Y1005092D01*
Y999050D01*
G01Y1005092D02*
X593274Y1006133D01*
X594316Y1006967D01*
X595774Y1007383D01*
X597232Y1006967D01*
X598274Y1006133D01*
X598899Y1004883D01*
Y999050D01*
G01X611899D02*
Y1007383D01*
G01Y1005925D02*
X611066Y1006758D01*
X609816Y1007175D01*
X608357Y1007383D01*
X606899Y1006967D01*
X605649Y1006133D01*
X604815Y1004883D01*
X604399Y1003217D01*
X604815Y1001550D01*
X605649Y1000300D01*
X606899Y999467D01*
X608357Y999050D01*
X609816Y999258D01*
X611066Y999883D01*
X611899Y1000716D01*
G01X623649Y999050D02*
Y1011550D01*
G01X651732Y999050D02*
Y1007383D01*
G01Y1005717D02*
X652774Y1006550D01*
X653816Y1007175D01*
X655274Y1007383D01*
X656316Y1007175D01*
X657566Y1006550D01*
G01X667024Y1004675D02*
X673691D01*
X673066Y1006133D01*
X672024Y1006967D01*
X670566Y1007383D01*
X669107Y1007175D01*
X667857Y1006550D01*
X667024Y1005092D01*
X666607Y1003841D01*
Y1002592D01*
X667024Y1001342D01*
X668066Y1000091D01*
X669316Y999258D01*
X670774Y999050D01*
X672232Y999467D01*
X673691Y1000716D01*
G01X685649Y999050D02*
Y1011550D01*
G01X701149Y1007383D02*
Y999050D01*
G01Y1010716D02*
X700732Y1010925D01*
Y1011342D01*
X701149Y1011550D01*
X701566Y1011342D01*
Y1010925D01*
X701149Y1010716D01*
G01X713524Y1004675D02*
X720191D01*
X719566Y1006133D01*
X718524Y1006967D01*
X717066Y1007383D01*
X715607Y1007175D01*
X714357Y1006550D01*
X713524Y1005092D01*
X713107Y1003841D01*
Y1002592D01*
X713524Y1001342D01*
X714566Y1000091D01*
X715816Y999258D01*
X717274Y999050D01*
X718732Y999467D01*
X720191Y1000716D01*
G01X730899Y999050D02*
Y1009675D01*
X731316Y1010716D01*
X732149Y1011342D01*
X733399Y1011550D01*
X734649Y1011133D01*
X735274Y1010092D01*
G01X732774Y1006550D02*
X728607D01*
G01X240066Y1298950D02*
Y1311450D01*
X244232D01*
X245899Y1310825D01*
X247149Y1309992D01*
X248191Y1308742D01*
X249024Y1307283D01*
X249232Y1305200D01*
X249024Y1303117D01*
X248191Y1301658D01*
X247149Y1300408D01*
X245899Y1299575D01*
X244232Y1298950D01*
X240066D01*
G01X257024Y1304575D02*
X263691D01*
X263066Y1306033D01*
X262024Y1306867D01*
X260566Y1307283D01*
X259107Y1307075D01*
X257857Y1306450D01*
X257024Y1304992D01*
X256607Y1303741D01*
Y1302492D01*
X257024Y1301242D01*
X258066Y1299991D01*
X259316Y1299158D01*
X260774Y1298950D01*
X262232Y1299367D01*
X263691Y1300616D01*
G01X274399Y1298950D02*
Y1309575D01*
X274816Y1310616D01*
X275649Y1311242D01*
X276899Y1311450D01*
X278149Y1311033D01*
X278774Y1309992D01*
G01X276274Y1306450D02*
X272107D01*
G01X291149Y1307283D02*
Y1298950D01*
G01Y1310616D02*
X290732Y1310825D01*
Y1311242D01*
X291149Y1311450D01*
X291566Y1311242D01*
Y1310825D01*
X291149Y1310616D01*
G01X303107Y1298950D02*
Y1307283D01*
G01Y1305200D02*
X303941Y1306242D01*
X305191Y1307075D01*
X306857Y1307283D01*
X308316Y1307075D01*
X309566Y1306242D01*
X310191Y1304783D01*
Y1298950D01*
G01X319024Y1304575D02*
X325691D01*
X325066Y1306033D01*
X324024Y1306867D01*
X322566Y1307283D01*
X321107Y1307075D01*
X319857Y1306450D01*
X319024Y1304992D01*
X318607Y1303741D01*
Y1302492D01*
X319024Y1301242D01*
X320066Y1299991D01*
X321316Y1299158D01*
X322774Y1298950D01*
X324232Y1299367D01*
X325691Y1300616D01*
G01X353149Y1311450D02*
Y1298950D01*
G01X350232Y1307283D02*
X356066D01*
G01X365107Y1298950D02*
Y1311450D01*
G01Y1305408D02*
X366149Y1306450D01*
X367191Y1307075D01*
X368857Y1307283D01*
X370107Y1307075D01*
X371566Y1306242D01*
X372191Y1304992D01*
Y1298950D01*
G01X381024Y1304575D02*
X387691D01*
X387066Y1306033D01*
X386024Y1306867D01*
X384566Y1307283D01*
X383107Y1307075D01*
X381857Y1306450D01*
X381024Y1304992D01*
X380607Y1303741D01*
Y1302492D01*
X381024Y1301242D01*
X382066Y1299991D01*
X383316Y1299158D01*
X384774Y1298950D01*
X386232Y1299367D01*
X387691Y1300616D01*
G01X396732Y1298950D02*
Y1307283D01*
G01Y1305617D02*
X397774Y1306450D01*
X398816Y1307075D01*
X400274Y1307283D01*
X401316Y1307075D01*
X402566Y1306450D01*
G01X408899Y1298950D02*
Y1307283D01*
G01Y1304992D02*
X409524Y1306033D01*
X410566Y1306867D01*
X412024Y1307283D01*
X413482Y1306867D01*
X414524Y1306033D01*
X415149Y1304992D01*
Y1298950D01*
G01Y1304992D02*
X415774Y1306033D01*
X416816Y1306867D01*
X418274Y1307283D01*
X419732Y1306867D01*
X420774Y1306033D01*
X421399Y1304783D01*
Y1298950D01*
G01X434399D02*
Y1307283D01*
G01Y1305825D02*
X433566Y1306658D01*
X432316Y1307075D01*
X430857Y1307283D01*
X429399Y1306867D01*
X428149Y1306033D01*
X427315Y1304783D01*
X426899Y1303117D01*
X427315Y1301450D01*
X428149Y1300200D01*
X429399Y1299367D01*
X430857Y1298950D01*
X432316Y1299158D01*
X433566Y1299783D01*
X434399Y1300616D01*
G01X446149Y1298950D02*
Y1311450D01*
G01X474232Y1298950D02*
Y1307283D01*
G01Y1305617D02*
X475274Y1306450D01*
X476316Y1307075D01*
X477774Y1307283D01*
X478816Y1307075D01*
X480066Y1306450D01*
G01X489524Y1304575D02*
X496191D01*
X495566Y1306033D01*
X494524Y1306867D01*
X493066Y1307283D01*
X491607Y1307075D01*
X490357Y1306450D01*
X489524Y1304992D01*
X489107Y1303741D01*
Y1302492D01*
X489524Y1301242D01*
X490566Y1299991D01*
X491816Y1299158D01*
X493274Y1298950D01*
X494732Y1299367D01*
X496191Y1300616D01*
G01X508149Y1298950D02*
Y1311450D01*
G01X523649Y1307283D02*
Y1298950D01*
G01Y1310616D02*
X523232Y1310825D01*
Y1311242D01*
X523649Y1311450D01*
X524066Y1311242D01*
Y1310825D01*
X523649Y1310616D01*
G01X536024Y1304575D02*
X542691D01*
X542066Y1306033D01*
X541024Y1306867D01*
X539566Y1307283D01*
X538107Y1307075D01*
X536857Y1306450D01*
X536024Y1304992D01*
X535607Y1303741D01*
Y1302492D01*
X536024Y1301242D01*
X537066Y1299991D01*
X538316Y1299158D01*
X539774Y1298950D01*
X541232Y1299367D01*
X542691Y1300616D01*
G01X553399Y1298950D02*
Y1309575D01*
X553816Y1310616D01*
X554649Y1311242D01*
X555899Y1311450D01*
X557149Y1311033D01*
X557774Y1309992D01*
G01X555274Y1306450D02*
X551107D01*
G01X588982Y1306242D02*
X587524Y1307075D01*
X586274Y1307283D01*
X584607Y1306867D01*
X583357Y1306033D01*
X582524Y1304575D01*
X582315Y1303117D01*
X582524Y1301658D01*
X583357Y1300408D01*
X584607Y1299367D01*
X586274Y1298950D01*
X587732Y1299367D01*
X588982Y1300200D01*
G01X601149Y1298950D02*
X599899Y1299158D01*
X598649Y1299991D01*
X597815Y1301450D01*
X597399Y1303117D01*
X597815Y1304783D01*
X598649Y1306242D01*
X599899Y1307075D01*
X601149Y1307283D01*
X602399Y1307075D01*
X603649Y1306242D01*
X604482Y1304783D01*
X604691Y1303117D01*
X604482Y1301450D01*
X603649Y1299991D01*
X602399Y1299158D01*
X601149Y1298950D01*
G01X613107D02*
Y1307283D01*
G01Y1305200D02*
X613941Y1306242D01*
X615191Y1307075D01*
X616857Y1307283D01*
X618316Y1307075D01*
X619566Y1306242D01*
X620191Y1304783D01*
Y1298950D01*
G01X628607D02*
Y1307283D01*
G01Y1305200D02*
X629441Y1306242D01*
X630691Y1307075D01*
X632357Y1307283D01*
X633816Y1307075D01*
X635066Y1306242D01*
X635691Y1304783D01*
Y1298950D01*
G01X644524Y1304575D02*
X651191D01*
X650566Y1306033D01*
X649524Y1306867D01*
X648066Y1307283D01*
X646607Y1307075D01*
X645357Y1306450D01*
X644524Y1304992D01*
X644107Y1303741D01*
Y1302492D01*
X644524Y1301242D01*
X645566Y1299991D01*
X646816Y1299158D01*
X648274Y1298950D01*
X649732Y1299367D01*
X651191Y1300616D01*
G01X666482Y1306242D02*
X665024Y1307075D01*
X663774Y1307283D01*
X662107Y1306867D01*
X660857Y1306033D01*
X660024Y1304575D01*
X659815Y1303117D01*
X660024Y1301658D01*
X660857Y1300408D01*
X662107Y1299367D01*
X663774Y1298950D01*
X665232Y1299367D01*
X666482Y1300200D01*
G01X678649Y1311450D02*
Y1298950D01*
G01X675732Y1307283D02*
X681566D01*
G01X912166Y870333D02*
X921332Y879500D01*
G01X916749Y881167D02*
Y868667D01*
G01X921332Y870333D02*
X912166Y879500D01*
G01X910499Y874917D02*
X922999D01*
G01X927666Y870333D02*
X936832Y879500D01*
G01X932249Y881167D02*
Y868667D01*
G01X936832Y870333D02*
X927666Y879500D01*
G01X925999Y874917D02*
X938499D01*
G01X943166Y870333D02*
X952332Y879500D01*
G01X947749Y881167D02*
Y868667D01*
G01X952332Y870333D02*
X943166Y879500D01*
G01X941499Y874917D02*
X953999D01*
G01X958666Y870333D02*
X967832Y879500D01*
G01X963249Y881167D02*
Y868667D01*
G01X967832Y870333D02*
X958666Y879500D01*
G01X956999Y874917D02*
X969499D01*
G01X978749Y870333D02*
X978332Y870542D01*
Y870958D01*
X978749Y871167D01*
X979166Y870958D01*
Y870542D01*
X978749Y870333D01*
G01Y875958D02*
X978332Y876167D01*
Y876583D01*
X978749Y876792D01*
X979166Y876583D01*
Y876167D01*
X978749Y875958D01*
G01X1007249Y883250D02*
X1012249D01*
G01X1009749D02*
Y870750D01*
G01X1007249D02*
X1012249D01*
G01X1022332Y867625D02*
X1023791Y866792D01*
X1025457Y866583D01*
X1026916Y866792D01*
X1028166Y867833D01*
X1028999Y869292D01*
Y879083D01*
G01Y877417D02*
X1028166Y878250D01*
X1026916Y878875D01*
X1025457Y879083D01*
X1023791Y878667D01*
X1022749Y877833D01*
X1021915Y876375D01*
X1021499Y874917D01*
X1021707Y873666D01*
X1022541Y872208D01*
X1023791Y871167D01*
X1025457Y870750D01*
X1026707Y870958D01*
X1028166Y871791D01*
X1028999Y872625D01*
G01X1037207Y870750D02*
Y879083D01*
G01Y877000D02*
X1038041Y878042D01*
X1039291Y878875D01*
X1040957Y879083D01*
X1042416Y878875D01*
X1043666Y878042D01*
X1044291Y876583D01*
Y870750D01*
G01X1056249D02*
X1054999Y870958D01*
X1053749Y871791D01*
X1052915Y873250D01*
X1052499Y874917D01*
X1052915Y876583D01*
X1053749Y878042D01*
X1054999Y878875D01*
X1056249Y879083D01*
X1057499Y878875D01*
X1058749Y878042D01*
X1059582Y876583D01*
X1059791Y874917D01*
X1059582Y873250D01*
X1058749Y871791D01*
X1057499Y870958D01*
X1056249Y870750D01*
G01X1068832D02*
Y879083D01*
G01Y877417D02*
X1069874Y878250D01*
X1070916Y878875D01*
X1072374Y879083D01*
X1073416Y878875D01*
X1074666Y878250D01*
G01X1084124Y876375D02*
X1090791D01*
X1090166Y877833D01*
X1089124Y878667D01*
X1087666Y879083D01*
X1086207Y878875D01*
X1084957Y878250D01*
X1084124Y876792D01*
X1083707Y875541D01*
Y874292D01*
X1084124Y873042D01*
X1085166Y871791D01*
X1086416Y870958D01*
X1087874Y870750D01*
X1089332Y871167D01*
X1090791Y872416D01*
G01X1118249Y870750D02*
Y883250D01*
X1115749Y880750D01*
G01Y870750D02*
X1120749D01*
G01X1142999D02*
Y879083D01*
G01Y876792D02*
X1143624Y877833D01*
X1144666Y878667D01*
X1146124Y879083D01*
X1147582Y878667D01*
X1148624Y877833D01*
X1149249Y876792D01*
Y870750D01*
G01Y876792D02*
X1149874Y877833D01*
X1150916Y878667D01*
X1152374Y879083D01*
X1153832Y878667D01*
X1154874Y877833D01*
X1155499Y876583D01*
Y870750D01*
G01X1164749Y879083D02*
Y870750D01*
G01Y882416D02*
X1164332Y882625D01*
Y883042D01*
X1164749Y883250D01*
X1165166Y883042D01*
Y882625D01*
X1164749Y882416D01*
G01X1180249Y870750D02*
Y883250D01*
G01X1206666Y870750D02*
Y883250D01*
X1210832D01*
X1212499Y882625D01*
X1213749Y881792D01*
X1214791Y880542D01*
X1215624Y879083D01*
X1215832Y877000D01*
X1215624Y874917D01*
X1214791Y873458D01*
X1213749Y872208D01*
X1212499Y871375D01*
X1210832Y870750D01*
X1206666D01*
G01X1224041Y874917D02*
X1229457D01*
G01X1246832Y882208D02*
X1245582Y882833D01*
X1244124Y883250D01*
X1242457D01*
X1240582Y882625D01*
X1239124Y881583D01*
X1238082Y880333D01*
X1237249Y878250D01*
X1237040Y876375D01*
X1237457Y874500D01*
X1238082Y873250D01*
X1239332Y872000D01*
X1240791Y871167D01*
X1242249Y870750D01*
X1243707D01*
X1245166Y871167D01*
X1246416Y871791D01*
X1247458Y872625D01*
G01X1257749Y870750D02*
X1256082Y870958D01*
X1254624Y871791D01*
X1253374Y873042D01*
X1252540Y874500D01*
X1252124Y876167D01*
Y877833D01*
X1252540Y879500D01*
X1253374Y880958D01*
X1254624Y882208D01*
X1256082Y883042D01*
X1257749Y883250D01*
X1259416Y883042D01*
X1260874Y882208D01*
X1262124Y880958D01*
X1262958Y879500D01*
X1263374Y877833D01*
Y876167D01*
X1262958Y874500D01*
X1262124Y873042D01*
X1260874Y871791D01*
X1259416Y870958D01*
X1257749Y870750D01*
G01X1268666D02*
Y883250D01*
X1272832D01*
X1274499Y882625D01*
X1275749Y881792D01*
X1276791Y880542D01*
X1277624Y879083D01*
X1277832Y877000D01*
X1277624Y874917D01*
X1276791Y873458D01*
X1275749Y872208D01*
X1274499Y871375D01*
X1272832Y870750D01*
X1268666D01*
G01X1292916D02*
X1284582D01*
Y883250D01*
X1292916D01*
G01X1289582Y877208D02*
X1284582D01*
G01X916357Y915650D02*
Y928150D01*
X925941Y915650D01*
Y928150D01*
G01X936649Y915650D02*
X935399Y915858D01*
X934149Y916691D01*
X933315Y918150D01*
X932899Y919817D01*
X933315Y921483D01*
X934149Y922942D01*
X935399Y923775D01*
X936649Y923983D01*
X937899Y923775D01*
X939149Y922942D01*
X939982Y921483D01*
X940191Y919817D01*
X939982Y918150D01*
X939149Y916691D01*
X937899Y915858D01*
X936649Y915650D01*
G01X952149Y928150D02*
Y915650D01*
G01X949232Y923983D02*
X955066D01*
G01X964524Y921275D02*
X971191D01*
X970566Y922733D01*
X969524Y923567D01*
X968066Y923983D01*
X966607Y923775D01*
X965357Y923150D01*
X964524Y921692D01*
X964107Y920441D01*
Y919192D01*
X964524Y917942D01*
X965566Y916691D01*
X966816Y915858D01*
X968274Y915650D01*
X969732Y916067D01*
X971191Y917316D01*
G01X980024Y917108D02*
X981066Y916275D01*
X982524Y915650D01*
X983774D01*
X985024Y916067D01*
X985857Y916691D01*
X986274Y917525D01*
X986066Y918775D01*
X985232Y919400D01*
X981482Y920650D01*
X980649Y922108D01*
X981066Y923150D01*
X981899Y923775D01*
X983149Y923983D01*
X984399Y923775D01*
X985649Y923150D01*
G01X998649Y915233D02*
X998232Y915442D01*
Y915858D01*
X998649Y916067D01*
X999066Y915858D01*
Y915442D01*
X998649Y915233D01*
G01Y920858D02*
X998232Y921067D01*
Y921483D01*
X998649Y921692D01*
X999066Y921483D01*
Y921067D01*
X998649Y920858D01*
G54D11*
G01X244732Y1098950D02*
X238066D01*
Y1108950D01*
X244732D01*
G01X242066Y1104117D02*
X238066D01*
G01X249199Y1098950D02*
X256199Y1108950D01*
G01X249199D02*
X256199Y1098950D01*
G01X263999Y1098617D02*
X263666Y1098783D01*
Y1099117D01*
X263999Y1099283D01*
X264332Y1099117D01*
Y1098783D01*
X263999Y1098617D01*
G01Y1103116D02*
X263666Y1103283D01*
Y1103617D01*
X263999Y1103783D01*
X264332Y1103617D01*
Y1103283D01*
X263999Y1103116D01*
G01X283432Y1098950D02*
Y1108950D01*
X289766D01*
G01X287432Y1104117D02*
X283432D01*
G01X294566Y1108950D02*
Y1098950D01*
X301232D01*
G01X305032D02*
X309199Y1108950D01*
X313366Y1098950D01*
G01X311866Y1102450D02*
X306532D01*
G01X316999Y1100283D02*
X318332Y1099450D01*
X319832Y1098950D01*
X321166D01*
X322499Y1099450D01*
X323499Y1100283D01*
X323999Y1101450D01*
X323666Y1102616D01*
X322832Y1103617D01*
X321332Y1104283D01*
X319332Y1104617D01*
X318166Y1105283D01*
X317666Y1106450D01*
X317999Y1107617D01*
X318832Y1108450D01*
X319999Y1108950D01*
X321166D01*
X322332Y1108617D01*
X323332Y1107783D01*
G01X328299Y1098950D02*
Y1108950D01*
G01X335299D02*
Y1098950D01*
G01Y1103950D02*
X328299D01*
G01X354399Y1108950D02*
Y1098950D01*
G01X350566Y1108950D02*
X358232D01*
G01X362366Y1098950D02*
Y1108950D01*
X366532D01*
X367866Y1108450D01*
X368699Y1107783D01*
X369032Y1106450D01*
X368699Y1105117D01*
X367699Y1104283D01*
X366532Y1103783D01*
X362366D01*
G01X366532D02*
X369032Y1098950D01*
G01X376999D02*
Y1108950D01*
X374999Y1106950D01*
G01Y1098950D02*
X378999D01*
G01X388299Y1108950D02*
X386965Y1108617D01*
X385966Y1107783D01*
X385299Y1106783D01*
X384799Y1105450D01*
X384632Y1103950D01*
X384799Y1102450D01*
X385299Y1101117D01*
X385966Y1100116D01*
X386965Y1099283D01*
X388299Y1098950D01*
X389632Y1099283D01*
X390632Y1100116D01*
X391299Y1101117D01*
X391799Y1102450D01*
X391966Y1103950D01*
X391799Y1105450D01*
X391299Y1106783D01*
X390632Y1107783D01*
X389632Y1108617D01*
X388299Y1108950D01*
G01X395932Y1100950D02*
X396932Y1099783D01*
X398265Y1099117D01*
X399766Y1098950D01*
X401099Y1099117D01*
X402432Y1099950D01*
X403266Y1100950D01*
X403432Y1101950D01*
X403099Y1103116D01*
X401932Y1103950D01*
X400766Y1104283D01*
X399266D01*
G01X400766D02*
X401766Y1104783D01*
X402599Y1105616D01*
X402932Y1106617D01*
X402599Y1107617D01*
X401766Y1108450D01*
X400266Y1108950D01*
X398766Y1108783D01*
X397266Y1108117D01*
G01X405899Y1095617D02*
X415899D01*
G01X419366Y1100116D02*
X420532Y1099283D01*
X421866Y1098950D01*
X423199Y1099283D01*
X424366Y1100283D01*
X425199Y1101783D01*
X425532Y1103283D01*
Y1105117D01*
X425199Y1106617D01*
X424366Y1107950D01*
X423366Y1108617D01*
X422199Y1108950D01*
X420865Y1108617D01*
X419866Y1107950D01*
X419199Y1106950D01*
X418866Y1105616D01*
X419199Y1104450D01*
X420032Y1103283D01*
X421032Y1102616D01*
X422199Y1102450D01*
X423532Y1102783D01*
X424532Y1103617D01*
X425532Y1105117D01*
G01X429832Y1100950D02*
X430832Y1099783D01*
X432165Y1099117D01*
X433666Y1098950D01*
X434999Y1099117D01*
X436332Y1099950D01*
X437166Y1100950D01*
X437332Y1101950D01*
X436999Y1103116D01*
X435832Y1103950D01*
X434666Y1104283D01*
X433166D01*
G01X434666D02*
X435666Y1104783D01*
X436499Y1105616D01*
X436832Y1106617D01*
X436499Y1107617D01*
X435666Y1108450D01*
X434166Y1108950D01*
X432666Y1108783D01*
X431166Y1108117D01*
G01X439799Y1095617D02*
X449799D01*
G01X452432Y1100950D02*
X453432Y1099783D01*
X454765Y1099117D01*
X456266Y1098950D01*
X457599Y1099117D01*
X458932Y1099950D01*
X459766Y1100950D01*
X459932Y1101950D01*
X459599Y1103116D01*
X458432Y1103950D01*
X457266Y1104283D01*
X455766D01*
G01X457266D02*
X458266Y1104783D01*
X459099Y1105616D01*
X459432Y1106617D01*
X459099Y1107617D01*
X458266Y1108450D01*
X456766Y1108950D01*
X455266Y1108783D01*
X453766Y1108117D01*
G01X467399Y1108950D02*
X466065Y1108617D01*
X465066Y1107783D01*
X464399Y1106783D01*
X463899Y1105450D01*
X463732Y1103950D01*
X463899Y1102450D01*
X464399Y1101117D01*
X465066Y1100116D01*
X466065Y1099283D01*
X467399Y1098950D01*
X468732Y1099283D01*
X469732Y1100116D01*
X470399Y1101117D01*
X470899Y1102450D01*
X471066Y1103950D01*
X470899Y1105450D01*
X470399Y1106783D01*
X469732Y1107783D01*
X468732Y1108617D01*
X467399Y1108950D01*
G01X478699Y1098617D02*
X478366Y1098783D01*
Y1099117D01*
X478699Y1099283D01*
X479032Y1099117D01*
Y1098783D01*
X478699Y1098617D01*
G01Y1103116D02*
X478366Y1103283D01*
Y1103617D01*
X478699Y1103783D01*
X479032Y1103617D01*
Y1103283D01*
X478699Y1103116D01*
G01X251732Y1240950D02*
X252732Y1239783D01*
X254065Y1239117D01*
X255566Y1238950D01*
X256899Y1239117D01*
X258232Y1239950D01*
X259066Y1240950D01*
X259232Y1241950D01*
X258899Y1243116D01*
X257732Y1243950D01*
X256566Y1244283D01*
X255066D01*
G01X256566D02*
X257566Y1244783D01*
X258399Y1245616D01*
X258732Y1246617D01*
X258399Y1247617D01*
X257566Y1248450D01*
X256066Y1248950D01*
X254566Y1248783D01*
X253066Y1248117D01*
G01X266699Y1238617D02*
X266366Y1238783D01*
Y1239117D01*
X266699Y1239283D01*
X267032Y1239117D01*
Y1238783D01*
X266699Y1238617D01*
G01X252232Y1263283D02*
X253232Y1264283D01*
X254399Y1264783D01*
X255732Y1264950D01*
X257399Y1264617D01*
X258566Y1263783D01*
X258899Y1262783D01*
X258732Y1261783D01*
X258066Y1260950D01*
X254732Y1259283D01*
X253232Y1258117D01*
X252232Y1256450D01*
X251899Y1254950D01*
X258899D01*
G01X266699Y1254617D02*
X266366Y1254783D01*
Y1255117D01*
X266699Y1255283D01*
X267032Y1255117D01*
Y1254783D01*
X266699Y1254617D01*
G01X255399Y1270950D02*
Y1280950D01*
X253399Y1278950D01*
G01Y1270950D02*
X257399D01*
G01X266699Y1270617D02*
X266366Y1270783D01*
Y1271117D01*
X266699Y1271283D01*
X267032Y1271117D01*
Y1270783D01*
X266699Y1270617D01*
G01X286132Y1270950D02*
Y1280950D01*
X292466D01*
G01X290132Y1276117D02*
X286132D01*
G01X297266Y1280950D02*
Y1270950D01*
X303932D01*
G01X307732D02*
X311899Y1280950D01*
X316066Y1270950D01*
G01X314566Y1274450D02*
X309232D01*
G01X319699Y1272283D02*
X321032Y1271450D01*
X322532Y1270950D01*
X323866D01*
X325199Y1271450D01*
X326199Y1272283D01*
X326699Y1273450D01*
X326366Y1274616D01*
X325532Y1275617D01*
X324032Y1276283D01*
X322032Y1276617D01*
X320866Y1277283D01*
X320366Y1278450D01*
X320699Y1279617D01*
X321532Y1280450D01*
X322699Y1280950D01*
X323866D01*
X325032Y1280617D01*
X326032Y1279783D01*
G01X330999Y1270950D02*
Y1280950D01*
G01X337999D02*
Y1270950D01*
G01Y1275950D02*
X330999D01*
G01X357099Y1280950D02*
Y1270950D01*
G01X353266Y1280950D02*
X360932D01*
G01X364899Y1270950D02*
Y1280950D01*
G01X371899D02*
Y1270950D01*
G01Y1275950D02*
X364899D01*
G01X375366Y1270950D02*
Y1280950D01*
X379699Y1272617D01*
X384032Y1280950D01*
Y1270950D01*
G01X387666Y1280950D02*
Y1270950D01*
X394332D01*
G01X402299D02*
Y1280950D01*
X400299Y1278950D01*
G01Y1270950D02*
X404299D01*
G01X413599Y1280950D02*
X412265Y1280617D01*
X411266Y1279783D01*
X410599Y1278783D01*
X410099Y1277450D01*
X409932Y1275950D01*
X410099Y1274450D01*
X410599Y1273117D01*
X411266Y1272116D01*
X412265Y1271283D01*
X413599Y1270950D01*
X414932Y1271283D01*
X415932Y1272116D01*
X416599Y1273117D01*
X417099Y1274450D01*
X417266Y1275950D01*
X417099Y1277450D01*
X416599Y1278783D01*
X415932Y1279783D01*
X414932Y1280617D01*
X413599Y1280950D01*
G01X436199Y1270617D02*
X435866Y1270783D01*
Y1271117D01*
X436199Y1271283D01*
X436532Y1271117D01*
Y1270783D01*
X436199Y1270617D01*
G01Y1275116D02*
X435866Y1275283D01*
Y1275617D01*
X436199Y1275783D01*
X436532Y1275617D01*
Y1275283D01*
X436199Y1275116D01*
G01X455632Y1270950D02*
Y1280950D01*
X461966D01*
G01X459632Y1276117D02*
X455632D01*
G01X467266Y1277616D02*
Y1272950D01*
X467932Y1271783D01*
X468932Y1271117D01*
X470099Y1270950D01*
X471266Y1271117D01*
X472266Y1271783D01*
X472932Y1272950D01*
G01Y1270950D02*
Y1277616D01*
G01X481399Y1270950D02*
Y1280950D01*
G01X492699Y1270950D02*
Y1280950D01*
G01X517966Y1276783D02*
X516799Y1277450D01*
X515799Y1277616D01*
X514466Y1277283D01*
X513466Y1276617D01*
X512799Y1275450D01*
X512632Y1274283D01*
X512799Y1273117D01*
X513466Y1272116D01*
X514466Y1271283D01*
X515799Y1270950D01*
X516966Y1271283D01*
X517966Y1271950D01*
G01X526599Y1270950D02*
X525599Y1271117D01*
X524599Y1271783D01*
X523932Y1272950D01*
X523599Y1274283D01*
X523932Y1275617D01*
X524599Y1276783D01*
X525599Y1277450D01*
X526599Y1277616D01*
X527599Y1277450D01*
X528599Y1276783D01*
X529266Y1275617D01*
X529432Y1274283D01*
X529266Y1272950D01*
X528599Y1271783D01*
X527599Y1271117D01*
X526599Y1270950D01*
G01X535066D02*
Y1277616D01*
G01Y1275950D02*
X535732Y1276783D01*
X536732Y1277450D01*
X538066Y1277616D01*
X539232Y1277450D01*
X540232Y1276783D01*
X540732Y1275617D01*
Y1270950D01*
G01X549199Y1280950D02*
Y1270950D01*
G01X546866Y1277616D02*
X551532D01*
G01X563499Y1270950D02*
Y1277616D01*
G01Y1276450D02*
X562832Y1277117D01*
X561832Y1277450D01*
X560666Y1277616D01*
X559499Y1277283D01*
X558499Y1276617D01*
X557832Y1275617D01*
X557499Y1274283D01*
X557832Y1272950D01*
X558499Y1271950D01*
X559499Y1271283D01*
X560666Y1270950D01*
X561832Y1271117D01*
X562832Y1271617D01*
X563499Y1272283D01*
G01X574466Y1276783D02*
X573299Y1277450D01*
X572299Y1277616D01*
X570966Y1277283D01*
X569966Y1276617D01*
X569299Y1275450D01*
X569132Y1274283D01*
X569299Y1273117D01*
X569966Y1272116D01*
X570966Y1271283D01*
X572299Y1270950D01*
X573466Y1271283D01*
X574466Y1271950D01*
G01X583099Y1280950D02*
Y1270950D01*
G01X580766Y1277616D02*
X585432D01*
G01X301032Y578250D02*
X294366D01*
Y588250D01*
X301032D01*
G01X298366Y583417D02*
X294366D01*
G01X305499Y578250D02*
X312499Y588250D01*
G01X305499D02*
X312499Y578250D01*
G01X320299Y577917D02*
X319966Y578083D01*
Y578417D01*
X320299Y578583D01*
X320632Y578417D01*
Y578083D01*
X320299Y577917D01*
G01Y582416D02*
X319966Y582583D01*
Y582917D01*
X320299Y583083D01*
X320632Y582917D01*
Y582583D01*
X320299Y582416D01*
G01X339732Y578250D02*
Y588250D01*
X346066D01*
G01X343732Y583417D02*
X339732D01*
G01X350866Y588250D02*
Y578250D01*
X357532D01*
G01X361332D02*
X365499Y588250D01*
X369666Y578250D01*
G01X368166Y581750D02*
X362832D01*
G01X373299Y579583D02*
X374632Y578750D01*
X376132Y578250D01*
X377466D01*
X378799Y578750D01*
X379799Y579583D01*
X380299Y580750D01*
X379966Y581916D01*
X379132Y582917D01*
X377632Y583583D01*
X375632Y583917D01*
X374466Y584583D01*
X373966Y585750D01*
X374299Y586917D01*
X375132Y587750D01*
X376299Y588250D01*
X377466D01*
X378632Y587917D01*
X379632Y587083D01*
G01X384599Y578250D02*
Y588250D01*
G01X391599D02*
Y578250D01*
G01Y583250D02*
X384599D01*
G01X410699Y588250D02*
Y578250D01*
G01X406866Y588250D02*
X414532D01*
G01X418666Y578250D02*
Y588250D01*
X422832D01*
X424166Y587750D01*
X424999Y587083D01*
X425332Y585750D01*
X424999Y584417D01*
X423999Y583583D01*
X422832Y583083D01*
X418666D01*
G01X422832D02*
X425332Y578250D01*
G01X430132Y582416D02*
X431299Y583583D01*
X432299Y584250D01*
X433632Y584583D01*
X434799Y584250D01*
X435632Y583583D01*
X436299Y582583D01*
X436466Y581417D01*
X436299Y580417D01*
X435632Y579416D01*
X434632Y578583D01*
X433466Y578250D01*
X432132Y578583D01*
X430966Y579583D01*
X430299Y581083D01*
X430132Y582750D01*
X430466Y584916D01*
X430966Y586083D01*
X431799Y587250D01*
X432966Y588083D01*
X434132Y588250D01*
X435299Y587917D01*
X436132Y587083D01*
G01X444599Y588250D02*
X443265Y587917D01*
X442266Y587083D01*
X441599Y586083D01*
X441099Y584750D01*
X440932Y583250D01*
X441099Y581750D01*
X441599Y580417D01*
X442266Y579416D01*
X443265Y578583D01*
X444599Y578250D01*
X445932Y578583D01*
X446932Y579416D01*
X447599Y580417D01*
X448099Y581750D01*
X448266Y583250D01*
X448099Y584750D01*
X447599Y586083D01*
X446932Y587083D01*
X445932Y587917D01*
X444599Y588250D01*
G01X452399Y578250D02*
X459399Y588250D01*
G01X452399D02*
X459399Y578250D01*
G01X467199D02*
Y588250D01*
X465199Y586250D01*
G01Y578250D02*
X469199D01*
G01X478499D02*
Y588250D01*
X476499Y586250D01*
G01Y578250D02*
X480499D01*
G01X486966Y579416D02*
X488132Y578583D01*
X489466Y578250D01*
X490799Y578583D01*
X491966Y579583D01*
X492799Y581083D01*
X493132Y582583D01*
Y584417D01*
X492799Y585917D01*
X491966Y587250D01*
X490966Y587917D01*
X489799Y588250D01*
X488465Y587917D01*
X487466Y587250D01*
X486799Y586250D01*
X486466Y584916D01*
X486799Y583750D01*
X487632Y582583D01*
X488632Y581916D01*
X489799Y581750D01*
X491132Y582083D01*
X492132Y582917D01*
X493132Y584417D01*
G01X496099Y574917D02*
X506099D01*
G01X509232Y586583D02*
X510232Y587583D01*
X511399Y588083D01*
X512732Y588250D01*
X514399Y587917D01*
X515566Y587083D01*
X515899Y586083D01*
X515732Y585083D01*
X515066Y584250D01*
X511732Y582583D01*
X510232Y581417D01*
X509232Y579750D01*
X508899Y578250D01*
X515899D01*
G01X523699Y588250D02*
X522365Y587917D01*
X521366Y587083D01*
X520699Y586083D01*
X520199Y584750D01*
X520032Y583250D01*
X520199Y581750D01*
X520699Y580417D01*
X521366Y579416D01*
X522365Y578583D01*
X523699Y578250D01*
X525032Y578583D01*
X526032Y579416D01*
X526699Y580417D01*
X527199Y581750D01*
X527366Y583250D01*
X527199Y584750D01*
X526699Y586083D01*
X526032Y587083D01*
X525032Y587917D01*
X523699Y588250D01*
G01X531499Y578250D02*
X538499Y588250D01*
G01X531499D02*
X538499Y578250D01*
G01X542632Y580250D02*
X543632Y579083D01*
X544965Y578417D01*
X546466Y578250D01*
X547799Y578417D01*
X549132Y579250D01*
X549966Y580250D01*
X550132Y581250D01*
X549799Y582416D01*
X548632Y583250D01*
X547466Y583583D01*
X545966D01*
G01X547466D02*
X548466Y584083D01*
X549299Y584916D01*
X549632Y585917D01*
X549299Y586917D01*
X548466Y587750D01*
X546966Y588250D01*
X545466Y588083D01*
X543966Y587417D01*
G01X557599Y588250D02*
X556265Y587917D01*
X555266Y587083D01*
X554599Y586083D01*
X554099Y584750D01*
X553932Y583250D01*
X554099Y581750D01*
X554599Y580417D01*
X555266Y579416D01*
X556265Y578583D01*
X557599Y578250D01*
X558932Y578583D01*
X559932Y579416D01*
X560599Y580417D01*
X561099Y581750D01*
X561266Y583250D01*
X561099Y584750D01*
X560599Y586083D01*
X559932Y587083D01*
X558932Y587917D01*
X557599Y588250D01*
G01X290666Y628050D02*
Y638050D01*
X298332Y628050D01*
Y638050D01*
G01X301632Y628050D02*
X305799Y638050D01*
X309966Y628050D01*
G01X308466Y631550D02*
X303132D01*
G01X312766Y628050D02*
Y638050D01*
X317099Y629717D01*
X321432Y638050D01*
Y628050D01*
G01X331732D02*
X325066D01*
Y638050D01*
X331732D01*
G01X329066Y633217D02*
X325066D01*
G01X339699Y627717D02*
X339366Y627883D01*
Y628217D01*
X339699Y628383D01*
X340032Y628217D01*
Y627883D01*
X339699Y627717D01*
G01Y632216D02*
X339366Y632383D01*
Y632717D01*
X339699Y632883D01*
X340032Y632717D01*
Y632383D01*
X339699Y632216D01*
G01X362299Y638050D02*
Y628050D01*
G01X358466Y638050D02*
X366132D01*
G01X370266Y628050D02*
Y638050D01*
X374432D01*
X375766Y637550D01*
X376599Y636883D01*
X376932Y635550D01*
X376599Y634217D01*
X375599Y633383D01*
X374432Y632883D01*
X370266D01*
G01X374432D02*
X376932Y628050D01*
G01X380732D02*
X384899Y638050D01*
X389066Y628050D01*
G01X387566Y631550D02*
X382232D01*
G01X392699Y628050D02*
X399699Y638050D01*
G01X392699D02*
X399699Y628050D01*
G01X408832Y633383D02*
X409499Y633883D01*
X409999Y634716D01*
X410332Y635883D01*
X409999Y636883D01*
X409332Y637550D01*
X408166Y638050D01*
X403666D01*
Y628050D01*
X409166D01*
X410332Y628717D01*
X410999Y629717D01*
X411332Y630883D01*
X410999Y632050D01*
X409999Y633050D01*
X408832Y633383D01*
X403666D01*
G01X413799Y624717D02*
X423799D01*
G01X433766Y637217D02*
X432766Y637717D01*
X431599Y638050D01*
X430266D01*
X428765Y637550D01*
X427599Y636717D01*
X426766Y635717D01*
X426099Y634050D01*
X425932Y632550D01*
X426266Y631050D01*
X426766Y630050D01*
X427766Y629050D01*
X428932Y628383D01*
X430099Y628050D01*
X431266D01*
X432432Y628383D01*
X433432Y628883D01*
X434266Y629550D01*
G01X437899Y628050D02*
X444899Y638050D01*
G01X437899D02*
X444899Y628050D01*
G01X449032D02*
Y638050D01*
X452366D01*
X453699Y637550D01*
X454699Y636883D01*
X455532Y635883D01*
X456199Y634716D01*
X456366Y633050D01*
X456199Y631383D01*
X455532Y630217D01*
X454699Y629216D01*
X453699Y628550D01*
X452366Y628050D01*
X449032D01*
G01X284399Y1262950D02*
X286732Y1252950D01*
X289399Y1262950D01*
X292066Y1252950D01*
X294399Y1262950D01*
G01X300699Y1259616D02*
Y1252950D01*
G01Y1262283D02*
X300366Y1262450D01*
Y1262783D01*
X300699Y1262950D01*
X301032Y1262783D01*
Y1262450D01*
X300699Y1262283D01*
G01X309499Y1254116D02*
X310332Y1253450D01*
X311499Y1252950D01*
X312499D01*
X313499Y1253283D01*
X314166Y1253783D01*
X314499Y1254450D01*
X314332Y1255450D01*
X313666Y1255950D01*
X310665Y1256950D01*
X309999Y1258117D01*
X310332Y1258950D01*
X310999Y1259450D01*
X311999Y1259616D01*
X312999Y1259450D01*
X313999Y1258950D01*
G01X323299Y1262950D02*
Y1252950D01*
G01X320966Y1259616D02*
X325632D01*
G01X332266Y1252950D02*
Y1259616D01*
G01Y1258283D02*
X333099Y1258950D01*
X333932Y1259450D01*
X335099Y1259616D01*
X335932Y1259450D01*
X336932Y1258950D01*
G01X345899Y1252950D02*
X344899Y1253117D01*
X343899Y1253783D01*
X343232Y1254950D01*
X342899Y1256283D01*
X343232Y1257617D01*
X343899Y1258783D01*
X344899Y1259450D01*
X345899Y1259616D01*
X346899Y1259450D01*
X347899Y1258783D01*
X348566Y1257617D01*
X348732Y1256283D01*
X348566Y1254950D01*
X347899Y1253783D01*
X346899Y1253117D01*
X345899Y1252950D01*
G01X354366D02*
Y1259616D01*
G01Y1257950D02*
X355032Y1258783D01*
X356032Y1259450D01*
X357366Y1259616D01*
X358532Y1259450D01*
X359532Y1258783D01*
X360032Y1257617D01*
Y1252950D01*
G01X379799Y1262950D02*
Y1252950D01*
G01X375966Y1262950D02*
X383632D01*
G01X387599Y1252950D02*
Y1262950D01*
G01X394599D02*
Y1252950D01*
G01Y1257950D02*
X387599D01*
G01X398066Y1252950D02*
Y1262950D01*
X402399Y1254617D01*
X406732Y1262950D01*
Y1252950D01*
G01X410366Y1262950D02*
Y1252950D01*
X417032D01*
G01X439299Y1262950D02*
Y1252950D01*
G01Y1254450D02*
X438632Y1253617D01*
X437632Y1253117D01*
X436466Y1252950D01*
X435132Y1253283D01*
X434132Y1254116D01*
X433466Y1255117D01*
X433299Y1256283D01*
X433466Y1257450D01*
X434132Y1258450D01*
X435132Y1259283D01*
X436466Y1259616D01*
X437632Y1259450D01*
X438466Y1259117D01*
X439299Y1258450D01*
G01X445099Y1257450D02*
X450432D01*
X449932Y1258617D01*
X449099Y1259283D01*
X447932Y1259616D01*
X446766Y1259450D01*
X445766Y1258950D01*
X445099Y1257783D01*
X444766Y1256783D01*
Y1255783D01*
X445099Y1254783D01*
X445932Y1253783D01*
X446932Y1253117D01*
X448099Y1252950D01*
X449266Y1253283D01*
X450432Y1254283D01*
G01X457899Y1252950D02*
Y1261450D01*
X458232Y1262283D01*
X458899Y1262783D01*
X459899Y1262950D01*
X460899Y1262617D01*
X461399Y1261783D01*
G01X459399Y1258950D02*
X456066D01*
G01X473199Y1252950D02*
Y1259616D01*
G01Y1258450D02*
X472532Y1259117D01*
X471532Y1259450D01*
X470366Y1259616D01*
X469199Y1259283D01*
X468199Y1258617D01*
X467532Y1257617D01*
X467199Y1256283D01*
X467532Y1254950D01*
X468199Y1253950D01*
X469199Y1253283D01*
X470366Y1252950D01*
X471532Y1253117D01*
X472532Y1253617D01*
X473199Y1254283D01*
G01X478666Y1259616D02*
Y1254950D01*
X479332Y1253783D01*
X480332Y1253117D01*
X481499Y1252950D01*
X482666Y1253117D01*
X483666Y1253783D01*
X484332Y1254950D01*
G01Y1252950D02*
Y1259616D01*
G01X492799Y1252950D02*
Y1262950D01*
G01X504099D02*
Y1252950D01*
G01X501766Y1259616D02*
X506432D01*
G01X526699Y1262950D02*
Y1252950D01*
G01X524366Y1259616D02*
X529032D01*
G01X534499Y1249950D02*
X535499Y1249617D01*
X536832Y1249950D01*
X537666Y1250617D01*
X538332Y1251450D01*
X539332Y1254116D01*
X541499Y1259616D01*
G01X536166D02*
X539332Y1254116D01*
G01X546299Y1249617D02*
Y1259616D01*
G01Y1258117D02*
X547132Y1258950D01*
X547965Y1259450D01*
X549299Y1259616D01*
X550466Y1259450D01*
X551632Y1258617D01*
X552132Y1257450D01*
X552299Y1256283D01*
X552132Y1255117D01*
X551632Y1253950D01*
X550632Y1253283D01*
X549299Y1252950D01*
X548132Y1253117D01*
X546966Y1253617D01*
X546299Y1254283D01*
G01X558099Y1257450D02*
X563432D01*
X562932Y1258617D01*
X562099Y1259283D01*
X560932Y1259616D01*
X559766Y1259450D01*
X558766Y1258950D01*
X558099Y1257783D01*
X557766Y1256783D01*
Y1255783D01*
X558099Y1254783D01*
X558932Y1253783D01*
X559932Y1253117D01*
X561099Y1252950D01*
X562266Y1253283D01*
X563432Y1254283D01*
G01X317732Y604250D02*
X311066D01*
Y614250D01*
X317732D01*
G01X315066Y609417D02*
X311066D01*
G01X325699Y603917D02*
X325366Y604083D01*
Y604417D01*
X325699Y604583D01*
X326032Y604417D01*
Y604083D01*
X325699Y603917D01*
G01Y608416D02*
X325366Y608583D01*
Y608917D01*
X325699Y609083D01*
X326032Y608917D01*
Y608583D01*
X325699Y608416D01*
G01X330232Y693650D02*
X323566D01*
Y703650D01*
X330232D01*
G01X327566Y698817D02*
X323566D01*
G01X316932Y772650D02*
Y782650D01*
X320266D01*
X321599Y782150D01*
X322599Y781483D01*
X323432Y780483D01*
X324099Y779316D01*
X324266Y777650D01*
X324099Y775983D01*
X323432Y774817D01*
X322599Y773816D01*
X321599Y773150D01*
X320266Y772650D01*
X316932D01*
G01X328632Y894250D02*
X321966D01*
Y904250D01*
X328632D01*
G01X325966Y899417D02*
X321966D01*
G01X333266Y904250D02*
Y894250D01*
X339932D01*
G01X344566Y904250D02*
Y894250D01*
X351232D01*
G01X357199Y904250D02*
X361199D01*
G01X359199D02*
Y894250D01*
G01X357199D02*
X361199D01*
G01X367166D02*
Y904250D01*
X371166D01*
X372499Y903750D01*
X373499Y902583D01*
X373832Y901250D01*
X373499Y899917D01*
X372666Y898917D01*
X371166Y898416D01*
X367166D01*
G01X378299Y895583D02*
X379632Y894750D01*
X381132Y894250D01*
X382466D01*
X383799Y894750D01*
X384799Y895583D01*
X385299Y896750D01*
X384966Y897916D01*
X384132Y898917D01*
X382632Y899583D01*
X380632Y899917D01*
X379466Y900583D01*
X378966Y901750D01*
X379299Y902917D01*
X380132Y903750D01*
X381299Y904250D01*
X382466D01*
X383632Y903917D01*
X384632Y903083D01*
G01X396432Y894250D02*
X389766D01*
Y904250D01*
X396432D01*
G01X393766Y899417D02*
X389766D01*
G01X415699Y904250D02*
Y894250D01*
G01X411866Y904250D02*
X419532D01*
G01X424166Y894250D02*
Y904250D01*
G01Y899417D02*
X424999Y900250D01*
X425832Y900750D01*
X427166Y900916D01*
X428166Y900750D01*
X429332Y900083D01*
X429832Y899083D01*
Y894250D01*
G01X435799Y898750D02*
X441132D01*
X440632Y899917D01*
X439799Y900583D01*
X438632Y900916D01*
X437466Y900750D01*
X436466Y900250D01*
X435799Y899083D01*
X435466Y898083D01*
Y897083D01*
X435799Y896083D01*
X436632Y895083D01*
X437632Y894417D01*
X438799Y894250D01*
X439966Y894583D01*
X441132Y895583D01*
G01X447266Y894250D02*
Y900916D01*
G01Y899583D02*
X448099Y900250D01*
X448932Y900750D01*
X450099Y900916D01*
X450932Y900750D01*
X451932Y900250D01*
G01X455899Y894250D02*
Y900916D01*
G01Y899083D02*
X456399Y899917D01*
X457232Y900583D01*
X458399Y900916D01*
X459565Y900583D01*
X460399Y899917D01*
X460899Y899083D01*
Y894250D01*
G01Y899083D02*
X461399Y899917D01*
X462232Y900583D01*
X463399Y900916D01*
X464566Y900583D01*
X465399Y899917D01*
X465899Y898917D01*
Y894250D01*
G01X475199D02*
Y900916D01*
G01Y899750D02*
X474532Y900417D01*
X473532Y900750D01*
X472366Y900916D01*
X471199Y900583D01*
X470199Y899917D01*
X469532Y898917D01*
X469199Y897583D01*
X469532Y896250D01*
X470199Y895250D01*
X471199Y894583D01*
X472366Y894250D01*
X473532Y894417D01*
X474532Y894917D01*
X475199Y895583D01*
G01X483499Y894250D02*
Y904250D01*
G01X327099Y1136150D02*
X331099D01*
G01X329099D02*
Y1126150D01*
G01X327099D02*
X331099D01*
G01X337566D02*
Y1132816D01*
G01Y1131150D02*
X338232Y1131983D01*
X339232Y1132650D01*
X340566Y1132816D01*
X341732Y1132650D01*
X342732Y1131983D01*
X343232Y1130817D01*
Y1126150D01*
G01X348866D02*
Y1132816D01*
G01Y1131150D02*
X349532Y1131983D01*
X350532Y1132650D01*
X351866Y1132816D01*
X353032Y1132650D01*
X354032Y1131983D01*
X354532Y1130817D01*
Y1126150D01*
G01X360499Y1130650D02*
X365832D01*
X365332Y1131817D01*
X364499Y1132483D01*
X363332Y1132816D01*
X362166Y1132650D01*
X361166Y1132150D01*
X360499Y1130983D01*
X360166Y1129983D01*
Y1128983D01*
X360499Y1127983D01*
X361332Y1126983D01*
X362332Y1126317D01*
X363499Y1126150D01*
X364666Y1126483D01*
X365832Y1127483D01*
G01X371966Y1126150D02*
Y1132816D01*
G01Y1131483D02*
X372799Y1132150D01*
X373632Y1132650D01*
X374799Y1132816D01*
X375632Y1132650D01*
X376632Y1132150D01*
G01X393232Y1126150D02*
Y1136150D01*
X396566D01*
X397899Y1135650D01*
X398899Y1134983D01*
X399732Y1133983D01*
X400399Y1132816D01*
X400566Y1131150D01*
X400399Y1129483D01*
X399732Y1128317D01*
X398899Y1127316D01*
X397899Y1126650D01*
X396566Y1126150D01*
X393232D01*
G01X408199Y1132816D02*
Y1126150D01*
G01Y1135483D02*
X407866Y1135650D01*
Y1135983D01*
X408199Y1136150D01*
X408532Y1135983D01*
Y1135650D01*
X408199Y1135483D01*
G01X422499Y1126150D02*
Y1132816D01*
G01Y1131650D02*
X421832Y1132317D01*
X420832Y1132650D01*
X419666Y1132816D01*
X418499Y1132483D01*
X417499Y1131817D01*
X416832Y1130817D01*
X416499Y1129483D01*
X416832Y1128150D01*
X417499Y1127150D01*
X418499Y1126483D01*
X419666Y1126150D01*
X420832Y1126317D01*
X421832Y1126817D01*
X422499Y1127483D01*
G01X425799Y1126150D02*
Y1132816D01*
G01Y1130983D02*
X426299Y1131817D01*
X427132Y1132483D01*
X428299Y1132816D01*
X429465Y1132483D01*
X430299Y1131817D01*
X430799Y1130983D01*
Y1126150D01*
G01Y1130983D02*
X431299Y1131817D01*
X432132Y1132483D01*
X433299Y1132816D01*
X434466Y1132483D01*
X435299Y1131817D01*
X435799Y1130817D01*
Y1126150D01*
G01X439599Y1130650D02*
X444932D01*
X444432Y1131817D01*
X443599Y1132483D01*
X442432Y1132816D01*
X441266Y1132650D01*
X440266Y1132150D01*
X439599Y1130983D01*
X439266Y1129983D01*
Y1128983D01*
X439599Y1127983D01*
X440432Y1126983D01*
X441432Y1126317D01*
X442599Y1126150D01*
X443766Y1126483D01*
X444932Y1127483D01*
G01X453399Y1136150D02*
Y1126150D01*
G01X451066Y1132816D02*
X455732D01*
G01X462199Y1130650D02*
X467532D01*
X467032Y1131817D01*
X466199Y1132483D01*
X465032Y1132816D01*
X463866Y1132650D01*
X462866Y1132150D01*
X462199Y1130983D01*
X461866Y1129983D01*
Y1128983D01*
X462199Y1127983D01*
X463032Y1126983D01*
X464032Y1126317D01*
X465199Y1126150D01*
X466366Y1126483D01*
X467532Y1127483D01*
G01X473666Y1126150D02*
Y1132816D01*
G01Y1131483D02*
X474499Y1132150D01*
X475332Y1132650D01*
X476499Y1132816D01*
X477332Y1132650D01*
X478332Y1132150D01*
G01X365732Y603950D02*
X359066D01*
Y613950D01*
X365732D01*
G01X363066Y609117D02*
X359066D01*
G01X371532Y605783D02*
X375866D01*
G01Y608783D02*
X371532D01*
G01X381332Y605450D02*
X382332Y604617D01*
X383499Y604117D01*
X384999Y603950D01*
X386499Y604283D01*
X387666Y604950D01*
X388499Y606117D01*
X388666Y607450D01*
X388332Y608783D01*
X387499Y609617D01*
X386332Y610283D01*
X385166Y610450D01*
X383999Y610283D01*
X382499Y609617D01*
X382999Y613950D01*
X387499D01*
G01X403266Y603950D02*
Y613950D01*
X407599Y605617D01*
X411932Y613950D01*
Y603950D01*
G01X416899Y613950D02*
X420899D01*
G01X418899D02*
Y603950D01*
G01X416899D02*
X420899D01*
G01X426866Y613950D02*
Y603950D01*
X433532D01*
G01X437999Y605283D02*
X439332Y604450D01*
X440832Y603950D01*
X442166D01*
X443499Y604450D01*
X444499Y605283D01*
X444999Y606450D01*
X444666Y607616D01*
X443832Y608617D01*
X442332Y609283D01*
X440332Y609617D01*
X439166Y610283D01*
X438666Y611450D01*
X438999Y612617D01*
X439832Y613450D01*
X440999Y613950D01*
X442166D01*
X443332Y613617D01*
X444332Y612783D01*
G01X463266Y600617D02*
X461599Y602283D01*
X460766Y603950D01*
Y610616D01*
X461599Y612283D01*
X463266Y613950D01*
G01X478399Y603950D02*
Y610616D01*
G01Y609450D02*
X477732Y610117D01*
X476732Y610450D01*
X475566Y610616D01*
X474399Y610283D01*
X473399Y609617D01*
X472732Y608617D01*
X472399Y607283D01*
X472732Y605950D01*
X473399Y604950D01*
X474399Y604283D01*
X475566Y603950D01*
X476732Y604117D01*
X477732Y604617D01*
X478399Y605283D01*
G01X486699Y603950D02*
Y613950D01*
G01X493832Y610616D02*
X495832Y603950D01*
X497999Y610616D01*
X500166Y603950D01*
X502166Y610616D01*
G01X512299Y603950D02*
Y610616D01*
G01Y609450D02*
X511632Y610117D01*
X510632Y610450D01*
X509466Y610616D01*
X508299Y610283D01*
X507299Y609617D01*
X506632Y608617D01*
X506299Y607283D01*
X506632Y605950D01*
X507299Y604950D01*
X508299Y604283D01*
X509466Y603950D01*
X510632Y604117D01*
X511632Y604617D01*
X512299Y605283D01*
G01X517099Y600950D02*
X518099Y600617D01*
X519432Y600950D01*
X520266Y601617D01*
X520932Y602450D01*
X521932Y605116D01*
X524099Y610616D01*
G01X518766D02*
X521932Y605116D01*
G01X529399D02*
X530232Y604450D01*
X531399Y603950D01*
X532399D01*
X533399Y604283D01*
X534066Y604783D01*
X534399Y605450D01*
X534232Y606450D01*
X533566Y606950D01*
X530565Y607950D01*
X529899Y609117D01*
X530232Y609950D01*
X530899Y610450D01*
X531899Y610616D01*
X532899Y610450D01*
X533899Y609950D01*
G01X551666Y603950D02*
Y613950D01*
G01X556999Y610616D02*
X551666Y606783D01*
G01X553832Y608283D02*
X557332Y603950D01*
G01X563299Y608450D02*
X568632D01*
X568132Y609617D01*
X567299Y610283D01*
X566132Y610616D01*
X564966Y610450D01*
X563966Y609950D01*
X563299Y608783D01*
X562966Y607783D01*
Y606783D01*
X563299Y605783D01*
X564132Y604783D01*
X565132Y604117D01*
X566299Y603950D01*
X567466Y604283D01*
X568632Y605283D01*
G01X574599Y608450D02*
X579932D01*
X579432Y609617D01*
X578599Y610283D01*
X577432Y610616D01*
X576266Y610450D01*
X575266Y609950D01*
X574599Y608783D01*
X574266Y607783D01*
Y606783D01*
X574599Y605783D01*
X575432Y604783D01*
X576432Y604117D01*
X577599Y603950D01*
X578766Y604283D01*
X579932Y605283D01*
G01X585399Y600617D02*
Y610616D01*
G01Y609117D02*
X586232Y609950D01*
X587065Y610450D01*
X588399Y610616D01*
X589566Y610450D01*
X590732Y609617D01*
X591232Y608450D01*
X591399Y607283D01*
X591232Y606117D01*
X590732Y604950D01*
X589732Y604283D01*
X588399Y603950D01*
X587232Y604117D01*
X586066Y604617D01*
X585399Y605283D01*
G01X607332Y605450D02*
X608332Y604617D01*
X609499Y604117D01*
X610999Y603950D01*
X612499Y604283D01*
X613666Y604950D01*
X614499Y606117D01*
X614666Y607450D01*
X614332Y608783D01*
X613499Y609617D01*
X612332Y610283D01*
X611166Y610450D01*
X609999Y610283D01*
X608499Y609617D01*
X608999Y613950D01*
X613499D01*
G01X628599Y603950D02*
Y610616D01*
G01Y608783D02*
X629099Y609617D01*
X629932Y610283D01*
X631099Y610616D01*
X632265Y610283D01*
X633099Y609617D01*
X633599Y608783D01*
Y603950D01*
G01Y608783D02*
X634099Y609617D01*
X634932Y610283D01*
X636099Y610616D01*
X637266Y610283D01*
X638099Y609617D01*
X638599Y608617D01*
Y603950D01*
G01X644899Y610616D02*
Y603950D01*
G01Y613283D02*
X644566Y613450D01*
Y613783D01*
X644899Y613950D01*
X645232Y613783D01*
Y613450D01*
X644899Y613283D01*
G01X656199Y603950D02*
Y613950D01*
G01X664999Y605116D02*
X665832Y604450D01*
X666999Y603950D01*
X667999D01*
X668999Y604283D01*
X669666Y604783D01*
X669999Y605450D01*
X669832Y606450D01*
X669166Y606950D01*
X666165Y607950D01*
X665499Y609117D01*
X665832Y609950D01*
X666499Y610450D01*
X667499Y610616D01*
X668499Y610450D01*
X669499Y609950D01*
G01X679632Y600617D02*
X681299Y602283D01*
X682132Y603950D01*
Y610616D01*
X681299Y612283D01*
X679632Y613950D01*
G01X398466Y676317D02*
X397466Y676817D01*
X396299Y677150D01*
X394966D01*
X393465Y676650D01*
X392299Y675817D01*
X391466Y674817D01*
X390799Y673150D01*
X390632Y671650D01*
X390966Y670150D01*
X391466Y669150D01*
X392466Y668150D01*
X393632Y667483D01*
X394799Y667150D01*
X395966D01*
X397132Y667483D01*
X398132Y667983D01*
X398966Y668650D01*
G01X390332Y864750D02*
X394499Y874750D01*
X398666Y864750D01*
G01X397166Y868250D02*
X391832D01*
G01X421889Y1183630D02*
X425222D01*
Y1180630D01*
X424222Y1179630D01*
X423056Y1178963D01*
X421389Y1178630D01*
X419722Y1178963D01*
X418556Y1179630D01*
X417556Y1180630D01*
X416889Y1181797D01*
X416556Y1183130D01*
Y1184297D01*
X416889Y1185296D01*
X417556Y1186463D01*
X418556Y1187463D01*
X419555Y1188130D01*
X420889Y1188630D01*
X422056D01*
X423389Y1188297D01*
X424389Y1187630D01*
G01X435189Y1178630D02*
Y1185296D01*
G01Y1184130D02*
X434522Y1184797D01*
X433522Y1185130D01*
X432356Y1185296D01*
X431189Y1184963D01*
X430189Y1184297D01*
X429522Y1183297D01*
X429189Y1181963D01*
X429522Y1180630D01*
X430189Y1179630D01*
X431189Y1178963D01*
X432356Y1178630D01*
X433522Y1178797D01*
X434522Y1179297D01*
X435189Y1179963D01*
G01X440489Y1175297D02*
Y1185296D01*
G01Y1183797D02*
X441322Y1184630D01*
X442155Y1185130D01*
X443489Y1185296D01*
X444656Y1185130D01*
X445822Y1184297D01*
X446322Y1183130D01*
X446489Y1181963D01*
X446322Y1180797D01*
X445822Y1179630D01*
X444822Y1178963D01*
X443489Y1178630D01*
X442322Y1178797D01*
X441156Y1179297D01*
X440489Y1179963D01*
G01X461089Y1188630D02*
X463422Y1178630D01*
X466089Y1188630D01*
X468756Y1178630D01*
X471089Y1188630D01*
G01X477389Y1185296D02*
Y1178630D01*
G01Y1187963D02*
X477056Y1188130D01*
Y1188463D01*
X477389Y1188630D01*
X477722Y1188463D01*
Y1188130D01*
X477389Y1187963D01*
G01X491689Y1188630D02*
Y1178630D01*
G01Y1180130D02*
X491022Y1179297D01*
X490022Y1178797D01*
X488856Y1178630D01*
X487522Y1178963D01*
X486522Y1179796D01*
X485856Y1180797D01*
X485689Y1181963D01*
X485856Y1183130D01*
X486522Y1184130D01*
X487522Y1184963D01*
X488856Y1185296D01*
X490022Y1185130D01*
X490856Y1184797D01*
X491689Y1184130D01*
G01X499989Y1188630D02*
Y1178630D01*
G01X497656Y1185296D02*
X502322D01*
G01X508456Y1178630D02*
Y1188630D01*
G01Y1183797D02*
X509289Y1184630D01*
X510122Y1185130D01*
X511456Y1185296D01*
X512456Y1185130D01*
X513622Y1184463D01*
X514122Y1183463D01*
Y1178630D01*
G01X424329Y1227230D02*
X422995Y1227397D01*
X421829Y1228063D01*
X420829Y1229063D01*
X420162Y1230230D01*
X419829Y1231563D01*
Y1232897D01*
X420162Y1234230D01*
X420829Y1235397D01*
X421829Y1236397D01*
X422995Y1237063D01*
X424329Y1237230D01*
X425662Y1237063D01*
X426829Y1236397D01*
X427829Y1235397D01*
X428496Y1234230D01*
X428829Y1232897D01*
Y1231563D01*
X428496Y1230230D01*
X427829Y1229063D01*
X426829Y1228063D01*
X425662Y1227397D01*
X424329Y1227230D01*
G01X432796Y1233896D02*
Y1229230D01*
X433462Y1228063D01*
X434462Y1227397D01*
X435629Y1227230D01*
X436796Y1227397D01*
X437796Y1228063D01*
X438462Y1229230D01*
G01Y1227230D02*
Y1233896D01*
G01X446929Y1237230D02*
Y1227230D01*
G01X444596Y1233896D02*
X449262D01*
G01X455729Y1231730D02*
X461062D01*
X460562Y1232897D01*
X459729Y1233563D01*
X458562Y1233896D01*
X457396Y1233730D01*
X456396Y1233230D01*
X455729Y1232063D01*
X455396Y1231063D01*
Y1230063D01*
X455729Y1229063D01*
X456562Y1228063D01*
X457562Y1227397D01*
X458729Y1227230D01*
X459896Y1227563D01*
X461062Y1228563D01*
G01X467196Y1227230D02*
Y1233896D01*
G01Y1232563D02*
X468029Y1233230D01*
X468862Y1233730D01*
X470029Y1233896D01*
X470862Y1233730D01*
X471862Y1233230D01*
G01X488462Y1227230D02*
Y1237230D01*
X491796D01*
X493129Y1236730D01*
X494129Y1236063D01*
X494962Y1235063D01*
X495629Y1233896D01*
X495796Y1232230D01*
X495629Y1230563D01*
X494962Y1229397D01*
X494129Y1228396D01*
X493129Y1227730D01*
X491796Y1227230D01*
X488462D01*
G01X503429Y1233896D02*
Y1227230D01*
G01Y1236563D02*
X503096Y1236730D01*
Y1237063D01*
X503429Y1237230D01*
X503762Y1237063D01*
Y1236730D01*
X503429Y1236563D01*
G01X517729Y1227230D02*
Y1233896D01*
G01Y1232730D02*
X517062Y1233397D01*
X516062Y1233730D01*
X514896Y1233896D01*
X513729Y1233563D01*
X512729Y1232897D01*
X512062Y1231897D01*
X511729Y1230563D01*
X512062Y1229230D01*
X512729Y1228230D01*
X513729Y1227563D01*
X514896Y1227230D01*
X516062Y1227397D01*
X517062Y1227897D01*
X517729Y1228563D01*
G01X521029Y1227230D02*
Y1233896D01*
G01Y1232063D02*
X521529Y1232897D01*
X522362Y1233563D01*
X523529Y1233896D01*
X524695Y1233563D01*
X525529Y1232897D01*
X526029Y1232063D01*
Y1227230D01*
G01Y1232063D02*
X526529Y1232897D01*
X527362Y1233563D01*
X528529Y1233896D01*
X529696Y1233563D01*
X530529Y1232897D01*
X531029Y1231897D01*
Y1227230D01*
G01X534829Y1231730D02*
X540162D01*
X539662Y1232897D01*
X538829Y1233563D01*
X537662Y1233896D01*
X536496Y1233730D01*
X535496Y1233230D01*
X534829Y1232063D01*
X534496Y1231063D01*
Y1230063D01*
X534829Y1229063D01*
X535662Y1228063D01*
X536662Y1227397D01*
X537829Y1227230D01*
X538996Y1227563D01*
X540162Y1228563D01*
G01X548629Y1237230D02*
Y1227230D01*
G01X546296Y1233896D02*
X550962D01*
G01X557429Y1231730D02*
X562762D01*
X562262Y1232897D01*
X561429Y1233563D01*
X560262Y1233896D01*
X559096Y1233730D01*
X558096Y1233230D01*
X557429Y1232063D01*
X557096Y1231063D01*
Y1230063D01*
X557429Y1229063D01*
X558262Y1228063D01*
X559262Y1227397D01*
X560429Y1227230D01*
X561596Y1227563D01*
X562762Y1228563D01*
G01X568896Y1227230D02*
Y1233896D01*
G01Y1232563D02*
X569729Y1233230D01*
X570562Y1233730D01*
X571729Y1233896D01*
X572562Y1233730D01*
X573562Y1233230D01*
G01X463432Y778483D02*
X464099Y778983D01*
X464599Y779816D01*
X464932Y780983D01*
X464599Y781983D01*
X463932Y782650D01*
X462766Y783150D01*
X458266D01*
Y773150D01*
X463766D01*
X464932Y773817D01*
X465599Y774817D01*
X465932Y775983D01*
X465599Y777150D01*
X464599Y778150D01*
X463432Y778483D01*
X458266D01*
G01X487399Y1106950D02*
X491399D01*
G01X489399D02*
Y1096950D01*
G01X487399D02*
X491399D01*
G01X497866D02*
Y1103616D01*
G01Y1101950D02*
X498532Y1102783D01*
X499532Y1103450D01*
X500866Y1103616D01*
X502032Y1103450D01*
X503032Y1102783D01*
X503532Y1101617D01*
Y1096950D01*
G01X509166D02*
Y1103616D01*
G01Y1101950D02*
X509832Y1102783D01*
X510832Y1103450D01*
X512166Y1103616D01*
X513332Y1103450D01*
X514332Y1102783D01*
X514832Y1101617D01*
Y1096950D01*
G01X520799Y1101450D02*
X526132D01*
X525632Y1102617D01*
X524799Y1103283D01*
X523632Y1103616D01*
X522466Y1103450D01*
X521466Y1102950D01*
X520799Y1101783D01*
X520466Y1100783D01*
Y1099783D01*
X520799Y1098783D01*
X521632Y1097783D01*
X522632Y1097117D01*
X523799Y1096950D01*
X524966Y1097283D01*
X526132Y1098283D01*
G01X532266Y1096950D02*
Y1103616D01*
G01Y1102283D02*
X533099Y1102950D01*
X533932Y1103450D01*
X535099Y1103616D01*
X535932Y1103450D01*
X536932Y1102950D01*
G01X553532Y1096950D02*
Y1106950D01*
X556866D01*
X558199Y1106450D01*
X559199Y1105783D01*
X560032Y1104783D01*
X560699Y1103616D01*
X560866Y1101950D01*
X560699Y1100283D01*
X560032Y1099117D01*
X559199Y1098116D01*
X558199Y1097450D01*
X556866Y1096950D01*
X553532D01*
G01X568499Y1103616D02*
Y1096950D01*
G01Y1106283D02*
X568166Y1106450D01*
Y1106783D01*
X568499Y1106950D01*
X568832Y1106783D01*
Y1106450D01*
X568499Y1106283D01*
G01X582799Y1096950D02*
Y1103616D01*
G01Y1102450D02*
X582132Y1103117D01*
X581132Y1103450D01*
X579966Y1103616D01*
X578799Y1103283D01*
X577799Y1102617D01*
X577132Y1101617D01*
X576799Y1100283D01*
X577132Y1098950D01*
X577799Y1097950D01*
X578799Y1097283D01*
X579966Y1096950D01*
X581132Y1097117D01*
X582132Y1097617D01*
X582799Y1098283D01*
G01X586099Y1096950D02*
Y1103616D01*
G01Y1101783D02*
X586599Y1102617D01*
X587432Y1103283D01*
X588599Y1103616D01*
X589765Y1103283D01*
X590599Y1102617D01*
X591099Y1101783D01*
Y1096950D01*
G01Y1101783D02*
X591599Y1102617D01*
X592432Y1103283D01*
X593599Y1103616D01*
X594766Y1103283D01*
X595599Y1102617D01*
X596099Y1101617D01*
Y1096950D01*
G01X599899Y1101450D02*
X605232D01*
X604732Y1102617D01*
X603899Y1103283D01*
X602732Y1103616D01*
X601566Y1103450D01*
X600566Y1102950D01*
X599899Y1101783D01*
X599566Y1100783D01*
Y1099783D01*
X599899Y1098783D01*
X600732Y1097783D01*
X601732Y1097117D01*
X602899Y1096950D01*
X604066Y1097283D01*
X605232Y1098283D01*
G01X613699Y1106950D02*
Y1096950D01*
G01X611366Y1103616D02*
X616032D01*
G01X622499Y1101450D02*
X627832D01*
X627332Y1102617D01*
X626499Y1103283D01*
X625332Y1103616D01*
X624166Y1103450D01*
X623166Y1102950D01*
X622499Y1101783D01*
X622166Y1100783D01*
Y1099783D01*
X622499Y1098783D01*
X623332Y1097783D01*
X624332Y1097117D01*
X625499Y1096950D01*
X626666Y1097283D01*
X627832Y1098283D01*
G01X633966Y1096950D02*
Y1103616D01*
G01Y1102283D02*
X634799Y1102950D01*
X635632Y1103450D01*
X636799Y1103616D01*
X637632Y1103450D01*
X638632Y1102950D01*
G01X645432Y1098783D02*
X649766D01*
G01Y1101783D02*
X645432D01*
G01X656066Y1098116D02*
X657232Y1097283D01*
X658566Y1096950D01*
X659899Y1097283D01*
X661066Y1098283D01*
X661899Y1099783D01*
X662232Y1101283D01*
Y1103117D01*
X661899Y1104617D01*
X661066Y1105950D01*
X660066Y1106617D01*
X658899Y1106950D01*
X657565Y1106617D01*
X656566Y1105950D01*
X655899Y1104950D01*
X655566Y1103616D01*
X655899Y1102450D01*
X656732Y1101283D01*
X657732Y1100616D01*
X658899Y1100450D01*
X660232Y1100783D01*
X661232Y1101617D01*
X662232Y1103117D01*
G01X666532Y1098950D02*
X667532Y1097783D01*
X668865Y1097117D01*
X670366Y1096950D01*
X671699Y1097117D01*
X673032Y1097950D01*
X673866Y1098950D01*
X674032Y1099950D01*
X673699Y1101116D01*
X672532Y1101950D01*
X671366Y1102283D01*
X669866D01*
G01X671366D02*
X672366Y1102783D01*
X673199Y1103616D01*
X673532Y1104617D01*
X673199Y1105617D01*
X672366Y1106450D01*
X670866Y1106950D01*
X669366Y1106783D01*
X667866Y1106117D01*
G01X492399Y1043950D02*
X495732D01*
Y1040950D01*
X494732Y1039950D01*
X493566Y1039283D01*
X491899Y1038950D01*
X490232Y1039283D01*
X489066Y1039950D01*
X488066Y1040950D01*
X487399Y1042117D01*
X487066Y1043450D01*
Y1044617D01*
X487399Y1045616D01*
X488066Y1046783D01*
X489066Y1047783D01*
X490065Y1048450D01*
X491399Y1048950D01*
X492566D01*
X493899Y1048617D01*
X494899Y1047950D01*
G01X505699Y1038950D02*
Y1045616D01*
G01Y1044450D02*
X505032Y1045117D01*
X504032Y1045450D01*
X502866Y1045616D01*
X501699Y1045283D01*
X500699Y1044617D01*
X500032Y1043617D01*
X499699Y1042283D01*
X500032Y1040950D01*
X500699Y1039950D01*
X501699Y1039283D01*
X502866Y1038950D01*
X504032Y1039117D01*
X505032Y1039617D01*
X505699Y1040283D01*
G01X510999Y1035617D02*
Y1045616D01*
G01Y1044117D02*
X511832Y1044950D01*
X512665Y1045450D01*
X513999Y1045616D01*
X515166Y1045450D01*
X516332Y1044617D01*
X516832Y1043450D01*
X516999Y1042283D01*
X516832Y1041117D01*
X516332Y1039950D01*
X515332Y1039283D01*
X513999Y1038950D01*
X512832Y1039117D01*
X511666Y1039617D01*
X510999Y1040283D01*
G01X531599Y1048950D02*
X533932Y1038950D01*
X536599Y1048950D01*
X539266Y1038950D01*
X541599Y1048950D01*
G01X547899Y1045616D02*
Y1038950D01*
G01Y1048283D02*
X547566Y1048450D01*
Y1048783D01*
X547899Y1048950D01*
X548232Y1048783D01*
Y1048450D01*
X547899Y1048283D01*
G01X562199Y1048950D02*
Y1038950D01*
G01Y1040450D02*
X561532Y1039617D01*
X560532Y1039117D01*
X559366Y1038950D01*
X558032Y1039283D01*
X557032Y1040116D01*
X556366Y1041117D01*
X556199Y1042283D01*
X556366Y1043450D01*
X557032Y1044450D01*
X558032Y1045283D01*
X559366Y1045616D01*
X560532Y1045450D01*
X561366Y1045117D01*
X562199Y1044450D01*
G01X570499Y1048950D02*
Y1038950D01*
G01X568166Y1045616D02*
X572832D01*
G01X578966Y1038950D02*
Y1048950D01*
G01Y1044117D02*
X579799Y1044950D01*
X580632Y1045450D01*
X581966Y1045616D01*
X582966Y1045450D01*
X584132Y1044783D01*
X584632Y1043783D01*
Y1038950D01*
G01X590932Y1040783D02*
X595266D01*
G01Y1043783D02*
X590932D01*
G01X600732Y1040950D02*
X601732Y1039783D01*
X603065Y1039117D01*
X604566Y1038950D01*
X605899Y1039117D01*
X607232Y1039950D01*
X608066Y1040950D01*
X608232Y1041950D01*
X607899Y1043116D01*
X606732Y1043950D01*
X605566Y1044283D01*
X604066D01*
G01X605566D02*
X606566Y1044783D01*
X607399Y1045616D01*
X607732Y1046617D01*
X607399Y1047617D01*
X606566Y1048450D01*
X605066Y1048950D01*
X603566Y1048783D01*
X602066Y1048117D01*
G01X615699Y1048950D02*
X614365Y1048617D01*
X613366Y1047783D01*
X612699Y1046783D01*
X612199Y1045450D01*
X612032Y1043950D01*
X612199Y1042450D01*
X612699Y1041117D01*
X613366Y1040116D01*
X614365Y1039283D01*
X615699Y1038950D01*
X617032Y1039283D01*
X618032Y1040116D01*
X618699Y1041117D01*
X619199Y1042450D01*
X619366Y1043950D01*
X619199Y1045450D01*
X618699Y1046783D01*
X618032Y1047783D01*
X617032Y1048617D01*
X615699Y1048950D01*
G01X489566Y1054950D02*
Y1064950D01*
X497232Y1054950D01*
Y1064950D01*
G01X501866Y1061616D02*
Y1056950D01*
X502532Y1055783D01*
X503532Y1055117D01*
X504699Y1054950D01*
X505866Y1055117D01*
X506866Y1055783D01*
X507532Y1056950D01*
G01Y1054950D02*
Y1061616D01*
G01X510999Y1054950D02*
Y1061616D01*
G01Y1059783D02*
X511499Y1060617D01*
X512332Y1061283D01*
X513499Y1061616D01*
X514665Y1061283D01*
X515499Y1060617D01*
X515999Y1059783D01*
Y1054950D01*
G01Y1059783D02*
X516499Y1060617D01*
X517332Y1061283D01*
X518499Y1061616D01*
X519666Y1061283D01*
X520499Y1060617D01*
X520999Y1059617D01*
Y1054950D01*
G01X535099Y1056283D02*
X536432Y1055450D01*
X537932Y1054950D01*
X539266D01*
X540599Y1055450D01*
X541599Y1056283D01*
X542099Y1057450D01*
X541766Y1058616D01*
X540932Y1059617D01*
X539432Y1060283D01*
X537432Y1060617D01*
X536266Y1061283D01*
X535766Y1062450D01*
X536099Y1063617D01*
X536932Y1064450D01*
X538099Y1064950D01*
X539266D01*
X540432Y1064617D01*
X541432Y1063783D01*
G01X546899Y1051617D02*
Y1061616D01*
G01Y1060117D02*
X547732Y1060950D01*
X548565Y1061450D01*
X549899Y1061616D01*
X551066Y1061450D01*
X552232Y1060617D01*
X552732Y1059450D01*
X552899Y1058283D01*
X552732Y1057117D01*
X552232Y1055950D01*
X551232Y1055283D01*
X549899Y1054950D01*
X548732Y1055117D01*
X547566Y1055617D01*
X546899Y1056283D01*
G01X561199Y1054950D02*
X560199Y1055117D01*
X559199Y1055783D01*
X558532Y1056950D01*
X558199Y1058283D01*
X558532Y1059617D01*
X559199Y1060783D01*
X560199Y1061450D01*
X561199Y1061616D01*
X562199Y1061450D01*
X563199Y1060783D01*
X563866Y1059617D01*
X564032Y1058283D01*
X563866Y1056950D01*
X563199Y1055783D01*
X562199Y1055117D01*
X561199Y1054950D01*
G01X569666D02*
Y1064950D01*
G01X574999Y1061616D02*
X569666Y1057783D01*
G01X571832Y1059283D02*
X575332Y1054950D01*
G01X581299Y1059450D02*
X586632D01*
X586132Y1060617D01*
X585299Y1061283D01*
X584132Y1061616D01*
X582966Y1061450D01*
X581966Y1060950D01*
X581299Y1059783D01*
X580966Y1058783D01*
Y1057783D01*
X581299Y1056783D01*
X582132Y1055783D01*
X583132Y1055117D01*
X584299Y1054950D01*
X585466Y1055283D01*
X586632Y1056283D01*
G01X592599Y1056116D02*
X593432Y1055450D01*
X594599Y1054950D01*
X595599D01*
X596599Y1055283D01*
X597266Y1055783D01*
X597599Y1056450D01*
X597432Y1057450D01*
X596766Y1057950D01*
X593765Y1058950D01*
X593099Y1060117D01*
X593432Y1060950D01*
X594099Y1061450D01*
X595099Y1061616D01*
X596099Y1061450D01*
X597099Y1060950D01*
G01X604232Y1056783D02*
X608566D01*
G01Y1059783D02*
X604232D01*
G01X619699Y1054950D02*
Y1064950D01*
X613532Y1057783D01*
X621866D01*
G01X491399Y1074950D02*
X490065Y1075117D01*
X488899Y1075783D01*
X487899Y1076783D01*
X487232Y1077950D01*
X486899Y1079283D01*
Y1080617D01*
X487232Y1081950D01*
X487899Y1083117D01*
X488899Y1084117D01*
X490065Y1084783D01*
X491399Y1084950D01*
X492732Y1084783D01*
X493899Y1084117D01*
X494899Y1083117D01*
X495566Y1081950D01*
X495899Y1080617D01*
Y1079283D01*
X495566Y1077950D01*
X494899Y1076783D01*
X493899Y1075783D01*
X492732Y1075117D01*
X491399Y1074950D01*
G01X499866Y1081616D02*
Y1076950D01*
X500532Y1075783D01*
X501532Y1075117D01*
X502699Y1074950D01*
X503866Y1075117D01*
X504866Y1075783D01*
X505532Y1076950D01*
G01Y1074950D02*
Y1081616D01*
G01X513999Y1084950D02*
Y1074950D01*
G01X511666Y1081616D02*
X516332D01*
G01X522799Y1079450D02*
X528132D01*
X527632Y1080617D01*
X526799Y1081283D01*
X525632Y1081616D01*
X524466Y1081450D01*
X523466Y1080950D01*
X522799Y1079783D01*
X522466Y1078783D01*
Y1077783D01*
X522799Y1076783D01*
X523632Y1075783D01*
X524632Y1075117D01*
X525799Y1074950D01*
X526966Y1075283D01*
X528132Y1076283D01*
G01X534266Y1074950D02*
Y1081616D01*
G01Y1080283D02*
X535099Y1080950D01*
X535932Y1081450D01*
X537099Y1081616D01*
X537932Y1081450D01*
X538932Y1080950D01*
G01X555532Y1074950D02*
Y1084950D01*
X558866D01*
X560199Y1084450D01*
X561199Y1083783D01*
X562032Y1082783D01*
X562699Y1081616D01*
X562866Y1079950D01*
X562699Y1078283D01*
X562032Y1077117D01*
X561199Y1076116D01*
X560199Y1075450D01*
X558866Y1074950D01*
X555532D01*
G01X570499Y1081616D02*
Y1074950D01*
G01Y1084283D02*
X570166Y1084450D01*
Y1084783D01*
X570499Y1084950D01*
X570832Y1084783D01*
Y1084450D01*
X570499Y1084283D01*
G01X584799Y1074950D02*
Y1081616D01*
G01Y1080450D02*
X584132Y1081117D01*
X583132Y1081450D01*
X581966Y1081616D01*
X580799Y1081283D01*
X579799Y1080617D01*
X579132Y1079617D01*
X578799Y1078283D01*
X579132Y1076950D01*
X579799Y1075950D01*
X580799Y1075283D01*
X581966Y1074950D01*
X583132Y1075117D01*
X584132Y1075617D01*
X584799Y1076283D01*
G01X588099Y1074950D02*
Y1081616D01*
G01Y1079783D02*
X588599Y1080617D01*
X589432Y1081283D01*
X590599Y1081616D01*
X591765Y1081283D01*
X592599Y1080617D01*
X593099Y1079783D01*
Y1074950D01*
G01Y1079783D02*
X593599Y1080617D01*
X594432Y1081283D01*
X595599Y1081616D01*
X596766Y1081283D01*
X597599Y1080617D01*
X598099Y1079617D01*
Y1074950D01*
G01X601899Y1079450D02*
X607232D01*
X606732Y1080617D01*
X605899Y1081283D01*
X604732Y1081616D01*
X603566Y1081450D01*
X602566Y1080950D01*
X601899Y1079783D01*
X601566Y1078783D01*
Y1077783D01*
X601899Y1076783D01*
X602732Y1075783D01*
X603732Y1075117D01*
X604899Y1074950D01*
X606066Y1075283D01*
X607232Y1076283D01*
G01X615699Y1084950D02*
Y1074950D01*
G01X613366Y1081616D02*
X618032D01*
G01X624499Y1079450D02*
X629832D01*
X629332Y1080617D01*
X628499Y1081283D01*
X627332Y1081616D01*
X626166Y1081450D01*
X625166Y1080950D01*
X624499Y1079783D01*
X624166Y1078783D01*
Y1077783D01*
X624499Y1076783D01*
X625332Y1075783D01*
X626332Y1075117D01*
X627499Y1074950D01*
X628666Y1075283D01*
X629832Y1076283D01*
G01X635966Y1074950D02*
Y1081616D01*
G01Y1080283D02*
X636799Y1080950D01*
X637632Y1081450D01*
X638799Y1081616D01*
X639632Y1081450D01*
X640632Y1080950D01*
G01X647432Y1076783D02*
X651766D01*
G01Y1079783D02*
X647432D01*
G01X660899Y1074950D02*
Y1084950D01*
X658899Y1082950D01*
G01Y1074950D02*
X662899D01*
G01X672199Y1084950D02*
X670865Y1084617D01*
X669866Y1083783D01*
X669199Y1082783D01*
X668699Y1081450D01*
X668532Y1079950D01*
X668699Y1078450D01*
X669199Y1077117D01*
X669866Y1076116D01*
X670865Y1075283D01*
X672199Y1074950D01*
X673532Y1075283D01*
X674532Y1076116D01*
X675199Y1077117D01*
X675699Y1078450D01*
X675866Y1079950D01*
X675699Y1081450D01*
X675199Y1082783D01*
X674532Y1083783D01*
X673532Y1084617D01*
X672199Y1084950D01*
G01X679832Y1076950D02*
X680832Y1075783D01*
X682165Y1075117D01*
X683666Y1074950D01*
X684999Y1075117D01*
X686332Y1075950D01*
X687166Y1076950D01*
X687332Y1077950D01*
X686999Y1079116D01*
X685832Y1079950D01*
X684666Y1080283D01*
X683166D01*
G01X684666D02*
X685666Y1080783D01*
X686499Y1081616D01*
X686832Y1082617D01*
X686499Y1083617D01*
X685666Y1084450D01*
X684166Y1084950D01*
X682666Y1084783D01*
X681166Y1084117D01*
G54D12*
G01X800199Y553050D02*
Y561050D01*
X803999D01*
G01X802599Y557183D02*
X800199D01*
G01X810099Y553050D02*
X809499Y553183D01*
X808899Y553717D01*
X808499Y554650D01*
X808299Y555717D01*
X808499Y556783D01*
X808899Y557717D01*
X809499Y558250D01*
X810099Y558383D01*
X810699Y558250D01*
X811299Y557717D01*
X811699Y556783D01*
X811799Y555717D01*
X811699Y554650D01*
X811299Y553717D01*
X810699Y553183D01*
X810099Y553050D01*
G01X816699D02*
Y558383D01*
G01Y557317D02*
X817199Y557850D01*
X817699Y558250D01*
X818399Y558383D01*
X818899Y558250D01*
X819499Y557850D01*
G01X832599Y556650D02*
X835799D01*
X835499Y557583D01*
X834999Y558117D01*
X834299Y558383D01*
X833599Y558250D01*
X832999Y557850D01*
X832599Y556917D01*
X832399Y556116D01*
Y555317D01*
X832599Y554517D01*
X833099Y553717D01*
X833699Y553183D01*
X834399Y553050D01*
X835099Y553317D01*
X835799Y554116D01*
G01X840599Y558383D02*
X843599Y553050D01*
G01Y558383D02*
X840599Y553050D01*
G01X851899D02*
Y558383D01*
G01Y557450D02*
X851499Y557983D01*
X850899Y558250D01*
X850199Y558383D01*
X849499Y558117D01*
X848899Y557583D01*
X848499Y556783D01*
X848299Y555717D01*
X848499Y554650D01*
X848899Y553850D01*
X849499Y553317D01*
X850199Y553050D01*
X850899Y553183D01*
X851499Y553583D01*
X851899Y554116D01*
G01X855099Y553050D02*
Y558383D01*
G01Y556917D02*
X855399Y557583D01*
X855899Y558117D01*
X856599Y558383D01*
X857299Y558117D01*
X857799Y557583D01*
X858099Y556917D01*
Y553050D01*
G01Y556917D02*
X858399Y557583D01*
X858899Y558117D01*
X859599Y558383D01*
X860299Y558117D01*
X860799Y557583D01*
X861099Y556783D01*
Y553050D01*
G01X864299Y550383D02*
Y558383D01*
G01Y557183D02*
X864799Y557850D01*
X865299Y558250D01*
X866099Y558383D01*
X866799Y558250D01*
X867499Y557583D01*
X867799Y556650D01*
X867899Y555717D01*
X867799Y554783D01*
X867499Y553850D01*
X866899Y553317D01*
X866099Y553050D01*
X865399Y553183D01*
X864699Y553583D01*
X864299Y554116D01*
G01X874099Y553050D02*
Y561050D01*
G01X880599Y556650D02*
X883799D01*
X883499Y557583D01*
X882999Y558117D01*
X882299Y558383D01*
X881599Y558250D01*
X880999Y557850D01*
X880599Y556917D01*
X880399Y556116D01*
Y555317D01*
X880599Y554517D01*
X881099Y553717D01*
X881699Y553183D01*
X882399Y553050D01*
X883099Y553317D01*
X883799Y554116D01*
G01X890099Y552783D02*
X889899Y552917D01*
Y553183D01*
X890099Y553317D01*
X890299Y553183D01*
Y552917D01*
X890099Y552783D01*
G01Y556383D02*
X889899Y556517D01*
Y556783D01*
X890099Y556917D01*
X890299Y556783D01*
Y556517D01*
X890099Y556383D01*
G01X903999Y553050D02*
Y561050D01*
G01X908199D02*
Y553050D01*
G01Y557050D02*
X903999D01*
G01X914099Y553050D02*
X913499Y553183D01*
X912899Y553717D01*
X912499Y554650D01*
X912299Y555717D01*
X912499Y556783D01*
X912899Y557717D01*
X913499Y558250D01*
X914099Y558383D01*
X914699Y558250D01*
X915299Y557717D01*
X915699Y556783D01*
X915799Y555717D01*
X915699Y554650D01*
X915299Y553717D01*
X914699Y553183D01*
X914099Y553050D01*
G01X922099D02*
Y561050D01*
G01X928599Y556650D02*
X931799D01*
X931499Y557583D01*
X930999Y558117D01*
X930299Y558383D01*
X929599Y558250D01*
X928999Y557850D01*
X928599Y556917D01*
X928399Y556116D01*
Y555317D01*
X928599Y554517D01*
X929099Y553717D01*
X929699Y553183D01*
X930399Y553050D01*
X931099Y553317D01*
X931799Y554116D01*
G01X943899Y553050D02*
Y561050D01*
X945899D01*
X946699Y560650D01*
X947299Y560117D01*
X947799Y559317D01*
X948199Y558383D01*
X948299Y557050D01*
X948199Y555717D01*
X947799Y554783D01*
X947299Y553983D01*
X946699Y553450D01*
X945899Y553050D01*
X943899D01*
G01X954099Y558383D02*
Y553050D01*
G01Y560517D02*
X953899Y560650D01*
Y560917D01*
X954099Y561050D01*
X954299Y560917D01*
Y560650D01*
X954099Y560517D01*
G01X963899Y553050D02*
Y558383D01*
G01Y557450D02*
X963499Y557983D01*
X962899Y558250D01*
X962199Y558383D01*
X961499Y558117D01*
X960899Y557583D01*
X960499Y556783D01*
X960299Y555717D01*
X960499Y554650D01*
X960899Y553850D01*
X961499Y553317D01*
X962199Y553050D01*
X962899Y553183D01*
X963499Y553583D01*
X963899Y554116D01*
G01X970099Y552783D02*
X969899Y552917D01*
Y553183D01*
X970099Y553317D01*
X970299Y553183D01*
Y552917D01*
X970099Y552783D01*
G01X975899Y554650D02*
X976499Y553717D01*
X977299Y553183D01*
X978199Y553050D01*
X978999Y553183D01*
X979799Y553850D01*
X980299Y554650D01*
X980399Y555450D01*
X980199Y556383D01*
X979499Y557050D01*
X978799Y557317D01*
X977899D01*
G01X978799D02*
X979399Y557717D01*
X979899Y558383D01*
X980099Y559183D01*
X979899Y559983D01*
X979399Y560650D01*
X978499Y561050D01*
X977599Y560917D01*
X976699Y560383D01*
G01X986099Y552783D02*
X985899Y552917D01*
Y553183D01*
X986099Y553317D01*
X986299Y553183D01*
Y552917D01*
X986099Y552783D01*
G01X994099Y553050D02*
Y561050D01*
X992899Y559450D01*
G01Y553050D02*
X995299D01*
G01X1002099D02*
X1002799Y553183D01*
X1003599Y553583D01*
X1004099Y554250D01*
X1004299Y555183D01*
X1004099Y556116D01*
X1003499Y556917D01*
X1002599Y557317D01*
X1001599D01*
X1000999Y557583D01*
X1000499Y558250D01*
X1000299Y559183D01*
X1000599Y560117D01*
X1001299Y560783D01*
X1002099Y561050D01*
X1002899Y560783D01*
X1003599Y560117D01*
X1003899Y559183D01*
X1003699Y558250D01*
X1003199Y557583D01*
X1002599Y557317D01*
X1001599D01*
X1000699Y556917D01*
X1000099Y556116D01*
X999899Y555183D01*
X1000099Y554250D01*
X1000599Y553583D01*
X1001399Y553183D01*
X1002099Y553050D01*
G01X1007099D02*
Y558383D01*
G01Y556917D02*
X1007399Y557583D01*
X1007899Y558117D01*
X1008599Y558383D01*
X1009299Y558117D01*
X1009799Y557583D01*
X1010099Y556917D01*
Y553050D01*
G01Y556917D02*
X1010399Y557583D01*
X1010899Y558117D01*
X1011599Y558383D01*
X1012299Y558117D01*
X1012799Y557583D01*
X1013099Y556783D01*
Y553050D01*
G01X1015099D02*
Y558383D01*
G01Y556917D02*
X1015399Y557583D01*
X1015899Y558117D01*
X1016599Y558383D01*
X1017299Y558117D01*
X1017799Y557583D01*
X1018099Y556917D01*
Y553050D01*
G01Y556917D02*
X1018399Y557583D01*
X1018899Y558117D01*
X1019599Y558383D01*
X1020299Y558117D01*
X1020799Y557583D01*
X1021099Y556783D01*
Y553050D01*
G01X1034099Y558383D02*
Y553050D01*
G01Y560517D02*
X1033899Y560650D01*
Y560917D01*
X1034099Y561050D01*
X1034299Y560917D01*
Y560650D01*
X1034099Y560517D01*
G01X1040599Y553983D02*
X1041099Y553450D01*
X1041799Y553050D01*
X1042399D01*
X1042999Y553317D01*
X1043399Y553717D01*
X1043599Y554250D01*
X1043499Y555050D01*
X1043099Y555450D01*
X1041299Y556250D01*
X1040899Y557183D01*
X1041099Y557850D01*
X1041499Y558250D01*
X1042099Y558383D01*
X1042699Y558250D01*
X1043299Y557850D01*
G01X1055099Y553050D02*
Y558383D01*
G01Y556917D02*
X1055399Y557583D01*
X1055899Y558117D01*
X1056599Y558383D01*
X1057299Y558117D01*
X1057799Y557583D01*
X1058099Y556917D01*
Y553050D01*
G01Y556917D02*
X1058399Y557583D01*
X1058899Y558117D01*
X1059599Y558383D01*
X1060299Y558117D01*
X1060799Y557583D01*
X1061099Y556783D01*
Y553050D01*
G01X1067899D02*
Y558383D01*
G01Y557450D02*
X1067499Y557983D01*
X1066899Y558250D01*
X1066199Y558383D01*
X1065499Y558117D01*
X1064899Y557583D01*
X1064499Y556783D01*
X1064299Y555717D01*
X1064499Y554650D01*
X1064899Y553850D01*
X1065499Y553317D01*
X1066199Y553050D01*
X1066899Y553183D01*
X1067499Y553583D01*
X1067899Y554116D01*
G01X1072699Y553050D02*
Y558383D01*
G01Y557317D02*
X1073199Y557850D01*
X1073699Y558250D01*
X1074399Y558383D01*
X1074899Y558250D01*
X1075499Y557850D01*
G01X1080399Y553050D02*
Y561050D01*
G01X1083599Y558383D02*
X1080399Y555317D01*
G01X1081699Y556517D02*
X1083799Y553050D01*
G01X1088599Y556650D02*
X1091799D01*
X1091499Y557583D01*
X1090999Y558117D01*
X1090299Y558383D01*
X1089599Y558250D01*
X1088999Y557850D01*
X1088599Y556917D01*
X1088399Y556116D01*
Y555317D01*
X1088599Y554517D01*
X1089099Y553717D01*
X1089699Y553183D01*
X1090399Y553050D01*
X1091099Y553317D01*
X1091799Y554116D01*
G01X1099899Y561050D02*
Y553050D01*
G01Y554250D02*
X1099499Y553583D01*
X1098899Y553183D01*
X1098199Y553050D01*
X1097399Y553317D01*
X1096799Y553983D01*
X1096399Y554783D01*
X1096299Y555717D01*
X1096399Y556650D01*
X1096799Y557450D01*
X1097399Y558117D01*
X1098199Y558383D01*
X1098899Y558250D01*
X1099399Y557983D01*
X1099899Y557450D01*
G01X1114099Y558383D02*
Y553050D01*
G01Y560517D02*
X1113899Y560650D01*
Y560917D01*
X1114099Y561050D01*
X1114299Y560917D01*
Y560650D01*
X1114099Y560517D01*
G01X1120399Y553050D02*
Y558383D01*
G01Y557050D02*
X1120799Y557717D01*
X1121399Y558250D01*
X1122199Y558383D01*
X1122899Y558250D01*
X1123499Y557717D01*
X1123799Y556783D01*
Y553050D01*
G01X1135099D02*
Y558383D01*
G01Y556917D02*
X1135399Y557583D01*
X1135899Y558117D01*
X1136599Y558383D01*
X1137299Y558117D01*
X1137799Y557583D01*
X1138099Y556917D01*
Y553050D01*
G01Y556917D02*
X1138399Y557583D01*
X1138899Y558117D01*
X1139599Y558383D01*
X1140299Y558117D01*
X1140799Y557583D01*
X1141099Y556783D01*
Y553050D01*
G01X1144599Y556650D02*
X1147799D01*
X1147499Y557583D01*
X1146999Y558117D01*
X1146299Y558383D01*
X1145599Y558250D01*
X1144999Y557850D01*
X1144599Y556917D01*
X1144399Y556116D01*
Y555317D01*
X1144599Y554517D01*
X1145099Y553717D01*
X1145699Y553183D01*
X1146399Y553050D01*
X1147099Y553317D01*
X1147799Y554116D01*
G01X1155699Y557717D02*
X1154999Y558250D01*
X1154399Y558383D01*
X1153599Y558117D01*
X1152999Y557583D01*
X1152599Y556650D01*
X1152499Y555717D01*
X1152599Y554783D01*
X1152999Y553983D01*
X1153599Y553317D01*
X1154399Y553050D01*
X1155099Y553317D01*
X1155699Y553850D01*
G01X1160399Y553050D02*
Y561050D01*
G01Y557183D02*
X1160899Y557850D01*
X1161399Y558250D01*
X1162199Y558383D01*
X1162799Y558250D01*
X1163499Y557717D01*
X1163799Y556917D01*
Y553050D01*
G01X1171899D02*
Y558383D01*
G01Y557450D02*
X1171499Y557983D01*
X1170899Y558250D01*
X1170199Y558383D01*
X1169499Y558117D01*
X1168899Y557583D01*
X1168499Y556783D01*
X1168299Y555717D01*
X1168499Y554650D01*
X1168899Y553850D01*
X1169499Y553317D01*
X1170199Y553050D01*
X1170899Y553183D01*
X1171499Y553583D01*
X1171899Y554116D01*
G01X1176399Y553050D02*
Y558383D01*
G01Y557050D02*
X1176799Y557717D01*
X1177399Y558250D01*
X1178199Y558383D01*
X1178899Y558250D01*
X1179499Y557717D01*
X1179799Y556783D01*
Y553050D01*
G01X1186099Y558383D02*
Y553050D01*
G01Y560517D02*
X1185899Y560650D01*
Y560917D01*
X1186099Y561050D01*
X1186299Y560917D01*
Y560650D01*
X1186099Y560517D01*
G01X1195699Y557717D02*
X1194999Y558250D01*
X1194399Y558383D01*
X1193599Y558117D01*
X1192999Y557583D01*
X1192599Y556650D01*
X1192499Y555717D01*
X1192599Y554783D01*
X1192999Y553983D01*
X1193599Y553317D01*
X1194399Y553050D01*
X1195099Y553317D01*
X1195699Y553850D01*
G01X1203899Y553050D02*
Y558383D01*
G01Y557450D02*
X1203499Y557983D01*
X1202899Y558250D01*
X1202199Y558383D01*
X1201499Y558117D01*
X1200899Y557583D01*
X1200499Y556783D01*
X1200299Y555717D01*
X1200499Y554650D01*
X1200899Y553850D01*
X1201499Y553317D01*
X1202199Y553050D01*
X1202899Y553183D01*
X1203499Y553583D01*
X1203899Y554116D01*
G01X1210099Y553050D02*
Y561050D01*
G01X1227899D02*
Y553050D01*
G01Y554250D02*
X1227499Y553583D01*
X1226899Y553183D01*
X1226199Y553050D01*
X1225399Y553317D01*
X1224799Y553983D01*
X1224399Y554783D01*
X1224299Y555717D01*
X1224399Y556650D01*
X1224799Y557450D01*
X1225399Y558117D01*
X1226199Y558383D01*
X1226899Y558250D01*
X1227399Y557983D01*
X1227899Y557450D01*
G01X1232699Y553050D02*
Y558383D01*
G01Y557317D02*
X1233199Y557850D01*
X1233699Y558250D01*
X1234399Y558383D01*
X1234899Y558250D01*
X1235499Y557850D01*
G01X1243899Y553050D02*
Y558383D01*
G01Y557450D02*
X1243499Y557983D01*
X1242899Y558250D01*
X1242199Y558383D01*
X1241499Y558117D01*
X1240899Y557583D01*
X1240499Y556783D01*
X1240299Y555717D01*
X1240499Y554650D01*
X1240899Y553850D01*
X1241499Y553317D01*
X1242199Y553050D01*
X1242899Y553183D01*
X1243499Y553583D01*
X1243899Y554116D01*
G01X1247599Y558383D02*
X1248799Y553050D01*
X1250099Y558383D01*
X1251399Y553050D01*
X1252599Y558383D01*
G01X1258099D02*
Y553050D01*
G01Y560517D02*
X1257899Y560650D01*
Y560917D01*
X1258099Y561050D01*
X1258299Y560917D01*
Y560650D01*
X1258099Y560517D01*
G01X1264399Y553050D02*
Y558383D01*
G01Y557050D02*
X1264799Y557717D01*
X1265399Y558250D01*
X1266199Y558383D01*
X1266899Y558250D01*
X1267499Y557717D01*
X1267799Y556783D01*
Y553050D01*
G01X1272699Y551050D02*
X1273399Y550517D01*
X1274199Y550383D01*
X1274899Y550517D01*
X1275499Y551183D01*
X1275899Y552117D01*
Y558383D01*
G01Y557317D02*
X1275499Y557850D01*
X1274899Y558250D01*
X1274199Y558383D01*
X1273399Y558117D01*
X1272899Y557583D01*
X1272499Y556650D01*
X1272299Y555717D01*
X1272399Y554917D01*
X1272799Y553983D01*
X1273399Y553317D01*
X1274199Y553050D01*
X1274799Y553183D01*
X1275499Y553717D01*
X1275899Y554250D01*
G01X1291899Y553050D02*
Y558383D01*
G01Y557450D02*
X1291499Y557983D01*
X1290899Y558250D01*
X1290199Y558383D01*
X1289499Y558117D01*
X1288899Y557583D01*
X1288499Y556783D01*
X1288299Y555717D01*
X1288499Y554650D01*
X1288899Y553850D01*
X1289499Y553317D01*
X1290199Y553050D01*
X1290899Y553183D01*
X1291499Y553583D01*
X1291899Y554116D01*
G01X1296399Y553050D02*
Y558383D01*
G01Y557050D02*
X1296799Y557717D01*
X1297399Y558250D01*
X1298199Y558383D01*
X1298899Y558250D01*
X1299499Y557717D01*
X1299799Y556783D01*
Y553050D01*
G01X1307899Y561050D02*
Y553050D01*
G01Y554250D02*
X1307499Y553583D01*
X1306899Y553183D01*
X1306199Y553050D01*
X1305399Y553317D01*
X1304799Y553983D01*
X1304399Y554783D01*
X1304299Y555717D01*
X1304399Y556650D01*
X1304799Y557450D01*
X1305399Y558117D01*
X1306199Y558383D01*
X1306899Y558250D01*
X1307399Y557983D01*
X1307899Y557450D01*
G01X1320399Y553050D02*
Y561050D01*
G01Y557183D02*
X1320899Y557850D01*
X1321399Y558250D01*
X1322199Y558383D01*
X1322799Y558250D01*
X1323499Y557717D01*
X1323799Y556917D01*
Y553050D01*
G01X1330099D02*
X1329499Y553183D01*
X1328899Y553717D01*
X1328499Y554650D01*
X1328299Y555717D01*
X1328499Y556783D01*
X1328899Y557717D01*
X1329499Y558250D01*
X1330099Y558383D01*
X1330699Y558250D01*
X1331299Y557717D01*
X1331699Y556783D01*
X1331799Y555717D01*
X1331699Y554650D01*
X1331299Y553717D01*
X1330699Y553183D01*
X1330099Y553050D01*
G01X1338099D02*
Y561050D01*
G01X1344599Y556650D02*
X1347799D01*
X1347499Y557583D01*
X1346999Y558117D01*
X1346299Y558383D01*
X1345599Y558250D01*
X1344999Y557850D01*
X1344599Y556917D01*
X1344399Y556116D01*
Y555317D01*
X1344599Y554517D01*
X1345099Y553717D01*
X1345699Y553183D01*
X1346399Y553050D01*
X1347099Y553317D01*
X1347799Y554116D01*
G01X1359899Y553050D02*
Y561050D01*
X1361899D01*
X1362699Y560650D01*
X1363299Y560117D01*
X1363799Y559317D01*
X1364199Y558383D01*
X1364299Y557050D01*
X1364199Y555717D01*
X1363799Y554783D01*
X1363299Y553983D01*
X1362699Y553450D01*
X1361899Y553050D01*
X1359899D01*
G01X1370099Y558383D02*
Y553050D01*
G01Y560517D02*
X1369899Y560650D01*
Y560917D01*
X1370099Y561050D01*
X1370299Y560917D01*
Y560650D01*
X1370099Y560517D01*
G01X1379899Y553050D02*
Y558383D01*
G01Y557450D02*
X1379499Y557983D01*
X1378899Y558250D01*
X1378199Y558383D01*
X1377499Y558117D01*
X1376899Y557583D01*
X1376499Y556783D01*
X1376299Y555717D01*
X1376499Y554650D01*
X1376899Y553850D01*
X1377499Y553317D01*
X1378199Y553050D01*
X1378899Y553183D01*
X1379499Y553583D01*
X1379899Y554116D01*
G01X1386099Y552783D02*
X1385899Y552917D01*
Y553183D01*
X1386099Y553317D01*
X1386299Y553183D01*
Y552917D01*
X1386099Y552783D01*
G01X1402099Y553050D02*
Y561050D01*
X1400899Y559450D01*
G01Y553050D02*
X1403299D01*
G01X1408199Y559717D02*
X1408799Y560517D01*
X1409499Y560917D01*
X1410299Y561050D01*
X1411299Y560783D01*
X1411999Y560117D01*
X1412199Y559317D01*
X1412099Y558516D01*
X1411699Y557850D01*
X1409699Y556517D01*
X1408799Y555583D01*
X1408199Y554250D01*
X1407999Y553050D01*
X1412199D01*
G01X1416199Y556383D02*
X1416899Y557317D01*
X1417499Y557850D01*
X1418299Y558117D01*
X1418999Y557850D01*
X1419499Y557317D01*
X1419899Y556517D01*
X1419999Y555583D01*
X1419899Y554783D01*
X1419499Y553983D01*
X1418899Y553317D01*
X1418199Y553050D01*
X1417399Y553317D01*
X1416699Y554116D01*
X1416299Y555317D01*
X1416199Y556650D01*
X1416399Y558383D01*
X1416699Y559317D01*
X1417199Y560250D01*
X1417899Y560917D01*
X1418599Y561050D01*
X1419299Y560783D01*
X1419799Y560117D01*
G01X1423099Y553050D02*
Y558383D01*
G01Y556917D02*
X1423399Y557583D01*
X1423899Y558117D01*
X1424599Y558383D01*
X1425299Y558117D01*
X1425799Y557583D01*
X1426099Y556917D01*
Y553050D01*
G01Y556917D02*
X1426399Y557583D01*
X1426899Y558117D01*
X1427599Y558383D01*
X1428299Y558117D01*
X1428799Y557583D01*
X1429099Y556783D01*
Y553050D01*
G01X1434099Y558383D02*
Y553050D01*
G01Y560517D02*
X1433899Y560650D01*
Y560917D01*
X1434099Y561050D01*
X1434299Y560917D01*
Y560650D01*
X1434099Y560517D01*
G01X1442099Y553050D02*
Y561050D01*
G01X1458099Y558383D02*
Y553050D01*
G01Y560517D02*
X1457899Y560650D01*
Y560917D01*
X1458099Y561050D01*
X1458299Y560917D01*
Y560650D01*
X1458099Y560517D01*
G01X1464599Y553983D02*
X1465099Y553450D01*
X1465799Y553050D01*
X1466399D01*
X1466999Y553317D01*
X1467399Y553717D01*
X1467599Y554250D01*
X1467499Y555050D01*
X1467099Y555450D01*
X1465299Y556250D01*
X1464899Y557183D01*
X1465099Y557850D01*
X1465499Y558250D01*
X1466099Y558383D01*
X1466699Y558250D01*
X1467299Y557850D01*
G01X1479099Y553050D02*
Y558383D01*
G01Y556917D02*
X1479399Y557583D01*
X1479899Y558117D01*
X1480599Y558383D01*
X1481299Y558117D01*
X1481799Y557583D01*
X1482099Y556917D01*
Y553050D01*
G01Y556917D02*
X1482399Y557583D01*
X1482899Y558117D01*
X1483599Y558383D01*
X1484299Y558117D01*
X1484799Y557583D01*
X1485099Y556783D01*
Y553050D01*
G01X1491899D02*
Y558383D01*
G01Y557450D02*
X1491499Y557983D01*
X1490899Y558250D01*
X1490199Y558383D01*
X1489499Y558117D01*
X1488899Y557583D01*
X1488499Y556783D01*
X1488299Y555717D01*
X1488499Y554650D01*
X1488899Y553850D01*
X1489499Y553317D01*
X1490199Y553050D01*
X1490899Y553183D01*
X1491499Y553583D01*
X1491899Y554116D01*
G01X1496699Y553050D02*
Y558383D01*
G01Y557317D02*
X1497199Y557850D01*
X1497699Y558250D01*
X1498399Y558383D01*
X1498899Y558250D01*
X1499499Y557850D01*
G01X1504399Y553050D02*
Y561050D01*
G01X1507599Y558383D02*
X1504399Y555317D01*
G01X1505699Y556517D02*
X1507799Y553050D01*
G01X1512599Y556650D02*
X1515799D01*
X1515499Y557583D01*
X1514999Y558117D01*
X1514299Y558383D01*
X1513599Y558250D01*
X1512999Y557850D01*
X1512599Y556917D01*
X1512399Y556116D01*
Y555317D01*
X1512599Y554517D01*
X1513099Y553717D01*
X1513699Y553183D01*
X1514399Y553050D01*
X1515099Y553317D01*
X1515799Y554116D01*
G01X1523899Y561050D02*
Y553050D01*
G01Y554250D02*
X1523499Y553583D01*
X1522899Y553183D01*
X1522199Y553050D01*
X1521399Y553317D01*
X1520799Y553983D01*
X1520399Y554783D01*
X1520299Y555717D01*
X1520399Y556650D01*
X1520799Y557450D01*
X1521399Y558117D01*
X1522199Y558383D01*
X1522899Y558250D01*
X1523399Y557983D01*
X1523899Y557450D01*
G01X1538099Y558383D02*
Y553050D01*
G01Y560517D02*
X1537899Y560650D01*
Y560917D01*
X1538099Y561050D01*
X1538299Y560917D01*
Y560650D01*
X1538099Y560517D01*
G01X1544399Y553050D02*
Y558383D01*
G01Y557050D02*
X1544799Y557717D01*
X1545399Y558250D01*
X1546199Y558383D01*
X1546899Y558250D01*
X1547499Y557717D01*
X1547799Y556783D01*
Y553050D01*
G01X1562699Y557050D02*
X1564699D01*
Y554650D01*
X1564099Y553850D01*
X1563399Y553317D01*
X1562399Y553050D01*
X1561399Y553317D01*
X1560699Y553850D01*
X1560099Y554650D01*
X1559699Y555583D01*
X1559499Y556650D01*
Y557583D01*
X1559699Y558383D01*
X1560099Y559317D01*
X1560699Y560117D01*
X1561299Y560650D01*
X1562099Y561050D01*
X1562799D01*
X1563599Y560783D01*
X1564199Y560250D01*
G01X1568599Y556650D02*
X1571799D01*
X1571499Y557583D01*
X1570999Y558117D01*
X1570299Y558383D01*
X1569599Y558250D01*
X1568999Y557850D01*
X1568599Y556917D01*
X1568399Y556116D01*
Y555317D01*
X1568599Y554517D01*
X1569099Y553717D01*
X1569699Y553183D01*
X1570399Y553050D01*
X1571099Y553317D01*
X1571799Y554116D01*
G01X1576699Y553050D02*
Y558383D01*
G01Y557317D02*
X1577199Y557850D01*
X1577699Y558250D01*
X1578399Y558383D01*
X1578899Y558250D01*
X1579499Y557850D01*
G01X1584299Y553050D02*
Y561050D01*
G01Y557050D02*
X1584799Y557850D01*
X1585399Y558250D01*
X1585999Y558383D01*
X1586899Y558117D01*
X1587499Y557583D01*
X1587899Y556650D01*
Y555583D01*
X1587699Y554517D01*
X1587299Y553717D01*
X1586599Y553183D01*
X1585999Y553050D01*
X1585399Y553183D01*
X1584799Y553583D01*
X1584299Y554250D01*
G01X1592599Y556650D02*
X1595799D01*
X1595499Y557583D01*
X1594999Y558117D01*
X1594299Y558383D01*
X1593599Y558250D01*
X1592999Y557850D01*
X1592599Y556917D01*
X1592399Y556116D01*
Y555317D01*
X1592599Y554517D01*
X1593099Y553717D01*
X1593699Y553183D01*
X1594399Y553050D01*
X1595099Y553317D01*
X1595799Y554116D01*
G01X1600699Y553050D02*
Y558383D01*
G01Y557317D02*
X1601199Y557850D01*
X1601699Y558250D01*
X1602399Y558383D01*
X1602899Y558250D01*
X1603499Y557850D01*
G01X1617499Y553050D02*
Y559850D01*
X1617699Y560517D01*
X1618099Y560917D01*
X1618699Y561050D01*
X1619299Y560783D01*
X1619599Y560117D01*
G01X1618399Y557850D02*
X1616399D01*
G01X1626099Y558383D02*
Y553050D01*
G01Y560517D02*
X1625899Y560650D01*
Y560917D01*
X1626099Y561050D01*
X1626299Y560917D01*
Y560650D01*
X1626099Y560517D01*
G01X1634099Y553050D02*
Y561050D01*
G01X1640599Y556650D02*
X1643799D01*
X1643499Y557583D01*
X1642999Y558117D01*
X1642299Y558383D01*
X1641599Y558250D01*
X1640999Y557850D01*
X1640599Y556917D01*
X1640399Y556116D01*
Y555317D01*
X1640599Y554517D01*
X1641099Y553717D01*
X1641699Y553183D01*
X1642399Y553050D01*
X1643099Y553317D01*
X1643799Y554116D01*
G01X1650099Y552783D02*
X1649899Y552917D01*
Y553183D01*
X1650099Y553317D01*
X1650299Y553183D01*
Y552917D01*
X1650099Y552783D01*
G01X800199Y585150D02*
Y579417D01*
X800599Y578216D01*
X801399Y577417D01*
X802399Y577150D01*
X803399Y577417D01*
X804199Y578216D01*
X804599Y579417D01*
Y585150D01*
G01X808699Y577150D02*
Y582483D01*
G01Y581150D02*
X809099Y581817D01*
X809699Y582350D01*
X810499Y582483D01*
X811199Y582350D01*
X811799Y581817D01*
X812099Y580883D01*
Y577150D01*
G01X818399Y582483D02*
Y577150D01*
G01Y584617D02*
X818199Y584750D01*
Y585017D01*
X818399Y585150D01*
X818599Y585017D01*
Y584750D01*
X818399Y584617D01*
G01X826399Y585150D02*
Y577150D01*
G01X824999Y582483D02*
X827799D01*
G01X843999Y581817D02*
X843299Y582350D01*
X842699Y582483D01*
X841899Y582217D01*
X841299Y581683D01*
X840899Y580750D01*
X840799Y579817D01*
X840899Y578883D01*
X841299Y578083D01*
X841899Y577417D01*
X842699Y577150D01*
X843399Y577417D01*
X843999Y577950D01*
G01X850399Y577150D02*
X849799Y577283D01*
X849199Y577817D01*
X848799Y578750D01*
X848599Y579817D01*
X848799Y580883D01*
X849199Y581817D01*
X849799Y582350D01*
X850399Y582483D01*
X850999Y582350D01*
X851599Y581817D01*
X851999Y580883D01*
X852099Y579817D01*
X851999Y578750D01*
X851599Y577817D01*
X850999Y577283D01*
X850399Y577150D01*
G01X856699D02*
Y582483D01*
G01Y581150D02*
X857099Y581817D01*
X857699Y582350D01*
X858499Y582483D01*
X859199Y582350D01*
X859799Y581817D01*
X860099Y580883D01*
Y577150D01*
G01X864599Y582483D02*
X866399Y577150D01*
X868199Y582483D01*
G01X872899Y580750D02*
X876099D01*
X875799Y581683D01*
X875299Y582217D01*
X874599Y582483D01*
X873899Y582350D01*
X873299Y581950D01*
X872899Y581017D01*
X872699Y580216D01*
Y579417D01*
X872899Y578617D01*
X873399Y577817D01*
X873999Y577283D01*
X874699Y577150D01*
X875399Y577417D01*
X876099Y578216D01*
G01X880999Y577150D02*
Y582483D01*
G01Y581417D02*
X881499Y581950D01*
X881999Y582350D01*
X882699Y582483D01*
X883199Y582350D01*
X883799Y581950D01*
G01X888899Y578083D02*
X889399Y577550D01*
X890099Y577150D01*
X890699D01*
X891299Y577417D01*
X891699Y577817D01*
X891899Y578350D01*
X891799Y579150D01*
X891399Y579550D01*
X889599Y580350D01*
X889199Y581283D01*
X889399Y581950D01*
X889799Y582350D01*
X890399Y582483D01*
X890999Y582350D01*
X891599Y581950D01*
G01X898399Y582483D02*
Y577150D01*
G01Y584617D02*
X898199Y584750D01*
Y585017D01*
X898399Y585150D01*
X898599Y585017D01*
Y584750D01*
X898399Y584617D01*
G01X906399Y577150D02*
X905799Y577283D01*
X905199Y577817D01*
X904799Y578750D01*
X904599Y579817D01*
X904799Y580883D01*
X905199Y581817D01*
X905799Y582350D01*
X906399Y582483D01*
X906999Y582350D01*
X907599Y581817D01*
X907999Y580883D01*
X908099Y579817D01*
X907999Y578750D01*
X907599Y577817D01*
X906999Y577283D01*
X906399Y577150D01*
G01X912699D02*
Y582483D01*
G01Y581150D02*
X913099Y581817D01*
X913699Y582350D01*
X914499Y582483D01*
X915199Y582350D01*
X915799Y581817D01*
X916099Y580883D01*
Y577150D01*
G01X928899Y580750D02*
X932099D01*
X931799Y581683D01*
X931299Y582217D01*
X930599Y582483D01*
X929899Y582350D01*
X929299Y581950D01*
X928899Y581017D01*
X928699Y580216D01*
Y579417D01*
X928899Y578617D01*
X929399Y577817D01*
X929999Y577283D01*
X930699Y577150D01*
X931399Y577417D01*
X932099Y578216D01*
G01X936999Y577150D02*
Y582483D01*
G01Y581417D02*
X937499Y581950D01*
X937999Y582350D01*
X938699Y582483D01*
X939199Y582350D01*
X939799Y581950D01*
G01X944999Y577150D02*
Y582483D01*
G01Y581417D02*
X945499Y581950D01*
X945999Y582350D01*
X946699Y582483D01*
X947199Y582350D01*
X947799Y581950D01*
G01X954399Y577150D02*
X953799Y577283D01*
X953199Y577817D01*
X952799Y578750D01*
X952599Y579817D01*
X952799Y580883D01*
X953199Y581817D01*
X953799Y582350D01*
X954399Y582483D01*
X954999Y582350D01*
X955599Y581817D01*
X955999Y580883D01*
X956099Y579817D01*
X955999Y578750D01*
X955599Y577817D01*
X954999Y577283D01*
X954399Y577150D01*
G01X960999D02*
Y582483D01*
G01Y581417D02*
X961499Y581950D01*
X961999Y582350D01*
X962699Y582483D01*
X963199Y582350D01*
X963799Y581950D01*
G01X976599Y577150D02*
Y585150D01*
G01Y581150D02*
X977099Y581950D01*
X977699Y582350D01*
X978299Y582483D01*
X979199Y582217D01*
X979799Y581683D01*
X980199Y580750D01*
Y579683D01*
X979999Y578617D01*
X979599Y577817D01*
X978899Y577283D01*
X978299Y577150D01*
X977699Y577283D01*
X977099Y577683D01*
X976599Y578350D01*
G01X984899Y580750D02*
X988099D01*
X987799Y581683D01*
X987299Y582217D01*
X986599Y582483D01*
X985899Y582350D01*
X985299Y581950D01*
X984899Y581017D01*
X984699Y580216D01*
Y579417D01*
X984899Y578617D01*
X985399Y577817D01*
X985999Y577283D01*
X986699Y577150D01*
X987399Y577417D01*
X988099Y578216D01*
G01X994399Y585150D02*
Y577150D01*
G01X992999Y582483D02*
X995799D01*
G01X999899D02*
X1001099Y577150D01*
X1002399Y582483D01*
X1003699Y577150D01*
X1004899Y582483D01*
G01X1008899Y580750D02*
X1012099D01*
X1011799Y581683D01*
X1011299Y582217D01*
X1010599Y582483D01*
X1009899Y582350D01*
X1009299Y581950D01*
X1008899Y581017D01*
X1008699Y580216D01*
Y579417D01*
X1008899Y578617D01*
X1009399Y577817D01*
X1009999Y577283D01*
X1010699Y577150D01*
X1011399Y577417D01*
X1012099Y578216D01*
G01X1016899Y580750D02*
X1020099D01*
X1019799Y581683D01*
X1019299Y582217D01*
X1018599Y582483D01*
X1017899Y582350D01*
X1017299Y581950D01*
X1016899Y581017D01*
X1016699Y580216D01*
Y579417D01*
X1016899Y578617D01*
X1017399Y577817D01*
X1017999Y577283D01*
X1018699Y577150D01*
X1019399Y577417D01*
X1020099Y578216D01*
G01X1024699Y577150D02*
Y582483D01*
G01Y581150D02*
X1025099Y581817D01*
X1025699Y582350D01*
X1026499Y582483D01*
X1027199Y582350D01*
X1027799Y581817D01*
X1028099Y580883D01*
Y577150D01*
G01X1039399D02*
Y582483D01*
G01Y581017D02*
X1039699Y581683D01*
X1040199Y582217D01*
X1040899Y582483D01*
X1041599Y582217D01*
X1042099Y581683D01*
X1042399Y581017D01*
Y577150D01*
G01Y581017D02*
X1042699Y581683D01*
X1043199Y582217D01*
X1043899Y582483D01*
X1044599Y582217D01*
X1045099Y581683D01*
X1045399Y580883D01*
Y577150D01*
G01X1048899Y580750D02*
X1052099D01*
X1051799Y581683D01*
X1051299Y582217D01*
X1050599Y582483D01*
X1049899Y582350D01*
X1049299Y581950D01*
X1048899Y581017D01*
X1048699Y580216D01*
Y579417D01*
X1048899Y578617D01*
X1049399Y577817D01*
X1049999Y577283D01*
X1050699Y577150D01*
X1051399Y577417D01*
X1052099Y578216D01*
G01X1058399Y585150D02*
Y577150D01*
G01X1056999Y582483D02*
X1059799D01*
G01X1064999Y577150D02*
Y582483D01*
G01Y581417D02*
X1065499Y581950D01*
X1065999Y582350D01*
X1066699Y582483D01*
X1067199Y582350D01*
X1067799Y581950D01*
G01X1074399Y582483D02*
Y577150D01*
G01Y584617D02*
X1074199Y584750D01*
Y585017D01*
X1074399Y585150D01*
X1074599Y585017D01*
Y584750D01*
X1074399Y584617D01*
G01X1083999Y581817D02*
X1083299Y582350D01*
X1082699Y582483D01*
X1081899Y582217D01*
X1081299Y581683D01*
X1080899Y580750D01*
X1080799Y579817D01*
X1080899Y578883D01*
X1081299Y578083D01*
X1081899Y577417D01*
X1082699Y577150D01*
X1083399Y577417D01*
X1083999Y577950D01*
G01X1100199Y577150D02*
Y582483D01*
G01Y581550D02*
X1099799Y582083D01*
X1099199Y582350D01*
X1098499Y582483D01*
X1097799Y582217D01*
X1097199Y581683D01*
X1096799Y580883D01*
X1096599Y579817D01*
X1096799Y578750D01*
X1097199Y577950D01*
X1097799Y577417D01*
X1098499Y577150D01*
X1099199Y577283D01*
X1099799Y577683D01*
X1100199Y578216D01*
G01X1104699Y577150D02*
Y582483D01*
G01Y581150D02*
X1105099Y581817D01*
X1105699Y582350D01*
X1106499Y582483D01*
X1107199Y582350D01*
X1107799Y581817D01*
X1108099Y580883D01*
Y577150D01*
G01X1116199Y585150D02*
Y577150D01*
G01Y578350D02*
X1115799Y577683D01*
X1115199Y577283D01*
X1114499Y577150D01*
X1113699Y577417D01*
X1113099Y578083D01*
X1112699Y578883D01*
X1112599Y579817D01*
X1112699Y580750D01*
X1113099Y581550D01*
X1113699Y582217D01*
X1114499Y582483D01*
X1115199Y582350D01*
X1115699Y582083D01*
X1116199Y581550D01*
G01X1132399Y577150D02*
X1128399D01*
Y585150D01*
X1132399D01*
G01X1130799Y581283D02*
X1128399D01*
G01X1136699Y577150D02*
Y582483D01*
G01Y581150D02*
X1137099Y581817D01*
X1137699Y582350D01*
X1138499Y582483D01*
X1139199Y582350D01*
X1139799Y581817D01*
X1140099Y580883D01*
Y577150D01*
G01X1144999Y575150D02*
X1145699Y574617D01*
X1146499Y574483D01*
X1147199Y574617D01*
X1147799Y575283D01*
X1148199Y576217D01*
Y582483D01*
G01Y581417D02*
X1147799Y581950D01*
X1147199Y582350D01*
X1146499Y582483D01*
X1145699Y582217D01*
X1145199Y581683D01*
X1144799Y580750D01*
X1144599Y579817D01*
X1144699Y579017D01*
X1145099Y578083D01*
X1145699Y577417D01*
X1146499Y577150D01*
X1147099Y577283D01*
X1147799Y577817D01*
X1148199Y578350D01*
G01X1154399Y577150D02*
Y585150D01*
G01X1162399Y582483D02*
Y577150D01*
G01Y584617D02*
X1162199Y584750D01*
Y585017D01*
X1162399Y585150D01*
X1162599Y585017D01*
Y584750D01*
X1162399Y584617D01*
G01X1168899Y578083D02*
X1169399Y577550D01*
X1170099Y577150D01*
X1170699D01*
X1171299Y577417D01*
X1171699Y577817D01*
X1171899Y578350D01*
X1171799Y579150D01*
X1171399Y579550D01*
X1169599Y580350D01*
X1169199Y581283D01*
X1169399Y581950D01*
X1169799Y582350D01*
X1170399Y582483D01*
X1170999Y582350D01*
X1171599Y581950D01*
G01X1176699Y577150D02*
Y585150D01*
G01Y581283D02*
X1177199Y581950D01*
X1177699Y582350D01*
X1178499Y582483D01*
X1179099Y582350D01*
X1179799Y581817D01*
X1180099Y581017D01*
Y577150D01*
G01X1192899Y578083D02*
X1193399Y577550D01*
X1194099Y577150D01*
X1194699D01*
X1195299Y577417D01*
X1195699Y577817D01*
X1195899Y578350D01*
X1195799Y579150D01*
X1195399Y579550D01*
X1193599Y580350D01*
X1193199Y581283D01*
X1193399Y581950D01*
X1193799Y582350D01*
X1194399Y582483D01*
X1194999Y582350D01*
X1195599Y581950D01*
G01X1200299Y574750D02*
X1200899Y574483D01*
X1201699Y574750D01*
X1202199Y575283D01*
X1202599Y575950D01*
X1203199Y578083D01*
X1204499Y582483D01*
G01X1201299D02*
X1203199Y578083D01*
G01X1208899D02*
X1209399Y577550D01*
X1210099Y577150D01*
X1210699D01*
X1211299Y577417D01*
X1211699Y577817D01*
X1211899Y578350D01*
X1211799Y579150D01*
X1211399Y579550D01*
X1209599Y580350D01*
X1209199Y581283D01*
X1209399Y581950D01*
X1209799Y582350D01*
X1210399Y582483D01*
X1210999Y582350D01*
X1211599Y581950D01*
G01X1218399Y585150D02*
Y577150D01*
G01X1216999Y582483D02*
X1219799D01*
G01X1224899Y580750D02*
X1228099D01*
X1227799Y581683D01*
X1227299Y582217D01*
X1226599Y582483D01*
X1225899Y582350D01*
X1225299Y581950D01*
X1224899Y581017D01*
X1224699Y580216D01*
Y579417D01*
X1224899Y578617D01*
X1225399Y577817D01*
X1225999Y577283D01*
X1226699Y577150D01*
X1227399Y577417D01*
X1228099Y578216D01*
G01X1231399Y577150D02*
Y582483D01*
G01Y581017D02*
X1231699Y581683D01*
X1232199Y582217D01*
X1232899Y582483D01*
X1233599Y582217D01*
X1234099Y581683D01*
X1234399Y581017D01*
Y577150D01*
G01Y581017D02*
X1234699Y581683D01*
X1235199Y582217D01*
X1235899Y582483D01*
X1236599Y582217D01*
X1237099Y581683D01*
X1237399Y580883D01*
Y577150D01*
G01X1250399Y582483D02*
Y577150D01*
G01Y584617D02*
X1250199Y584750D01*
Y585017D01*
X1250399Y585150D01*
X1250599Y585017D01*
Y584750D01*
X1250399Y584617D01*
G01X1256899Y578083D02*
X1257399Y577550D01*
X1258099Y577150D01*
X1258699D01*
X1259299Y577417D01*
X1259699Y577817D01*
X1259899Y578350D01*
X1259799Y579150D01*
X1259399Y579550D01*
X1257599Y580350D01*
X1257199Y581283D01*
X1257399Y581950D01*
X1257799Y582350D01*
X1258399Y582483D01*
X1258999Y582350D01*
X1259599Y581950D01*
G01X1274399Y577150D02*
Y585150D01*
G01X1280899Y580750D02*
X1284099D01*
X1283799Y581683D01*
X1283299Y582217D01*
X1282599Y582483D01*
X1281899Y582350D01*
X1281299Y581950D01*
X1280899Y581017D01*
X1280699Y580216D01*
Y579417D01*
X1280899Y578617D01*
X1281399Y577817D01*
X1281999Y577283D01*
X1282699Y577150D01*
X1283399Y577417D01*
X1284099Y578216D01*
G01X1288899Y578083D02*
X1289399Y577550D01*
X1290099Y577150D01*
X1290699D01*
X1291299Y577417D01*
X1291699Y577817D01*
X1291899Y578350D01*
X1291799Y579150D01*
X1291399Y579550D01*
X1289599Y580350D01*
X1289199Y581283D01*
X1289399Y581950D01*
X1289799Y582350D01*
X1290399Y582483D01*
X1290999Y582350D01*
X1291599Y581950D01*
G01X1296899Y578083D02*
X1297399Y577550D01*
X1298099Y577150D01*
X1298699D01*
X1299299Y577417D01*
X1299699Y577817D01*
X1299899Y578350D01*
X1299799Y579150D01*
X1299399Y579550D01*
X1297599Y580350D01*
X1297199Y581283D01*
X1297399Y581950D01*
X1297799Y582350D01*
X1298399Y582483D01*
X1298999Y582350D01*
X1299599Y581950D01*
G01X1314399Y585150D02*
Y577150D01*
G01X1312999Y582483D02*
X1315799D01*
G01X1320699Y577150D02*
Y585150D01*
G01Y581283D02*
X1321199Y581950D01*
X1321699Y582350D01*
X1322499Y582483D01*
X1323099Y582350D01*
X1323799Y581817D01*
X1324099Y581017D01*
Y577150D01*
G01X1332199D02*
Y582483D01*
G01Y581550D02*
X1331799Y582083D01*
X1331199Y582350D01*
X1330499Y582483D01*
X1329799Y582217D01*
X1329199Y581683D01*
X1328799Y580883D01*
X1328599Y579817D01*
X1328799Y578750D01*
X1329199Y577950D01*
X1329799Y577417D01*
X1330499Y577150D01*
X1331199Y577283D01*
X1331799Y577683D01*
X1332199Y578216D01*
G01X1336699Y577150D02*
Y582483D01*
G01Y581150D02*
X1337099Y581817D01*
X1337699Y582350D01*
X1338499Y582483D01*
X1339199Y582350D01*
X1339799Y581817D01*
X1340099Y580883D01*
Y577150D01*
G01X1354399D02*
Y585150D01*
X1353199Y583550D01*
G01Y577150D02*
X1355599D01*
G01X1367399D02*
Y582483D01*
G01Y581017D02*
X1367699Y581683D01*
X1368199Y582217D01*
X1368899Y582483D01*
X1369599Y582217D01*
X1370099Y581683D01*
X1370399Y581017D01*
Y577150D01*
G01Y581017D02*
X1370699Y581683D01*
X1371199Y582217D01*
X1371899Y582483D01*
X1372599Y582217D01*
X1373099Y581683D01*
X1373399Y580883D01*
Y577150D01*
G01X1378399Y582483D02*
Y577150D01*
G01Y584617D02*
X1378199Y584750D01*
Y585017D01*
X1378399Y585150D01*
X1378599Y585017D01*
Y584750D01*
X1378399Y584617D01*
G01X1386399Y577150D02*
Y585150D01*
G01X1394199Y575683D02*
X1394599Y577417D01*
G01X1408599Y574483D02*
Y582483D01*
G01Y581283D02*
X1409099Y581950D01*
X1409599Y582350D01*
X1410399Y582483D01*
X1411099Y582350D01*
X1411799Y581683D01*
X1412099Y580750D01*
X1412199Y579817D01*
X1412099Y578883D01*
X1411799Y577950D01*
X1411199Y577417D01*
X1410399Y577150D01*
X1409699Y577283D01*
X1408999Y577683D01*
X1408599Y578216D01*
G01X1418399Y577150D02*
Y585150D01*
G01X1424899Y580750D02*
X1428099D01*
X1427799Y581683D01*
X1427299Y582217D01*
X1426599Y582483D01*
X1425899Y582350D01*
X1425299Y581950D01*
X1424899Y581017D01*
X1424699Y580216D01*
Y579417D01*
X1424899Y578617D01*
X1425399Y577817D01*
X1425999Y577283D01*
X1426699Y577150D01*
X1427399Y577417D01*
X1428099Y578216D01*
G01X1436199Y577150D02*
Y582483D01*
G01Y581550D02*
X1435799Y582083D01*
X1435199Y582350D01*
X1434499Y582483D01*
X1433799Y582217D01*
X1433199Y581683D01*
X1432799Y580883D01*
X1432599Y579817D01*
X1432799Y578750D01*
X1433199Y577950D01*
X1433799Y577417D01*
X1434499Y577150D01*
X1435199Y577283D01*
X1435799Y577683D01*
X1436199Y578216D01*
G01X1440899Y578083D02*
X1441399Y577550D01*
X1442099Y577150D01*
X1442699D01*
X1443299Y577417D01*
X1443699Y577817D01*
X1443899Y578350D01*
X1443799Y579150D01*
X1443399Y579550D01*
X1441599Y580350D01*
X1441199Y581283D01*
X1441399Y581950D01*
X1441799Y582350D01*
X1442399Y582483D01*
X1442999Y582350D01*
X1443599Y581950D01*
G01X1448899Y580750D02*
X1452099D01*
X1451799Y581683D01*
X1451299Y582217D01*
X1450599Y582483D01*
X1449899Y582350D01*
X1449299Y581950D01*
X1448899Y581017D01*
X1448699Y580216D01*
Y579417D01*
X1448899Y578617D01*
X1449399Y577817D01*
X1449999Y577283D01*
X1450699Y577150D01*
X1451399Y577417D01*
X1452099Y578216D01*
G01X1465799Y577150D02*
Y583950D01*
X1465999Y584617D01*
X1466399Y585017D01*
X1466999Y585150D01*
X1467599Y584883D01*
X1467899Y584217D01*
G01X1466699Y581950D02*
X1464699D01*
G01X1474399Y577150D02*
X1473799Y577283D01*
X1473199Y577817D01*
X1472799Y578750D01*
X1472599Y579817D01*
X1472799Y580883D01*
X1473199Y581817D01*
X1473799Y582350D01*
X1474399Y582483D01*
X1474999Y582350D01*
X1475599Y581817D01*
X1475999Y580883D01*
X1476099Y579817D01*
X1475999Y578750D01*
X1475599Y577817D01*
X1474999Y577283D01*
X1474399Y577150D01*
G01X1482399D02*
Y585150D01*
G01X1490399Y577150D02*
Y585150D01*
G01X1498399Y577150D02*
X1497799Y577283D01*
X1497199Y577817D01*
X1496799Y578750D01*
X1496599Y579817D01*
X1496799Y580883D01*
X1497199Y581817D01*
X1497799Y582350D01*
X1498399Y582483D01*
X1498999Y582350D01*
X1499599Y581817D01*
X1499999Y580883D01*
X1500099Y579817D01*
X1499999Y578750D01*
X1499599Y577817D01*
X1498999Y577283D01*
X1498399Y577150D01*
G01X1503899Y582483D02*
X1505099Y577150D01*
X1506399Y582483D01*
X1507699Y577150D01*
X1508899Y582483D01*
G01X1519399Y577150D02*
Y582483D01*
G01Y581017D02*
X1519699Y581683D01*
X1520199Y582217D01*
X1520899Y582483D01*
X1521599Y582217D01*
X1522099Y581683D01*
X1522399Y581017D01*
Y577150D01*
G01Y581017D02*
X1522699Y581683D01*
X1523199Y582217D01*
X1523899Y582483D01*
X1524599Y582217D01*
X1525099Y581683D01*
X1525399Y580883D01*
Y577150D01*
G01X1528899Y580750D02*
X1532099D01*
X1531799Y581683D01*
X1531299Y582217D01*
X1530599Y582483D01*
X1529899Y582350D01*
X1529299Y581950D01*
X1528899Y581017D01*
X1528699Y580216D01*
Y579417D01*
X1528899Y578617D01*
X1529399Y577817D01*
X1529999Y577283D01*
X1530699Y577150D01*
X1531399Y577417D01*
X1532099Y578216D01*
G01X1539999Y581817D02*
X1539299Y582350D01*
X1538699Y582483D01*
X1537899Y582217D01*
X1537299Y581683D01*
X1536899Y580750D01*
X1536799Y579817D01*
X1536899Y578883D01*
X1537299Y578083D01*
X1537899Y577417D01*
X1538699Y577150D01*
X1539399Y577417D01*
X1539999Y577950D01*
G01X1544699Y577150D02*
Y585150D01*
G01Y581283D02*
X1545199Y581950D01*
X1545699Y582350D01*
X1546499Y582483D01*
X1547099Y582350D01*
X1547799Y581817D01*
X1548099Y581017D01*
Y577150D01*
G01X1556199D02*
Y582483D01*
G01Y581550D02*
X1555799Y582083D01*
X1555199Y582350D01*
X1554499Y582483D01*
X1553799Y582217D01*
X1553199Y581683D01*
X1552799Y580883D01*
X1552599Y579817D01*
X1552799Y578750D01*
X1553199Y577950D01*
X1553799Y577417D01*
X1554499Y577150D01*
X1555199Y577283D01*
X1555799Y577683D01*
X1556199Y578216D01*
G01X1560699Y577150D02*
Y582483D01*
G01Y581150D02*
X1561099Y581817D01*
X1561699Y582350D01*
X1562499Y582483D01*
X1563199Y582350D01*
X1563799Y581817D01*
X1564099Y580883D01*
Y577150D01*
G01X1570399Y582483D02*
Y577150D01*
G01Y584617D02*
X1570199Y584750D01*
Y585017D01*
X1570399Y585150D01*
X1570599Y585017D01*
Y584750D01*
X1570399Y584617D01*
G01X1579999Y581817D02*
X1579299Y582350D01*
X1578699Y582483D01*
X1577899Y582217D01*
X1577299Y581683D01*
X1576899Y580750D01*
X1576799Y579817D01*
X1576899Y578883D01*
X1577299Y578083D01*
X1577899Y577417D01*
X1578699Y577150D01*
X1579399Y577417D01*
X1579999Y577950D01*
G01X1588199Y577150D02*
Y582483D01*
G01Y581550D02*
X1587799Y582083D01*
X1587199Y582350D01*
X1586499Y582483D01*
X1585799Y582217D01*
X1585199Y581683D01*
X1584799Y580883D01*
X1584599Y579817D01*
X1584799Y578750D01*
X1585199Y577950D01*
X1585799Y577417D01*
X1586499Y577150D01*
X1587199Y577283D01*
X1587799Y577683D01*
X1588199Y578216D01*
G01X1594399Y577150D02*
Y585150D01*
G01X1612199D02*
Y577150D01*
G01Y578350D02*
X1611799Y577683D01*
X1611199Y577283D01*
X1610499Y577150D01*
X1609699Y577417D01*
X1609099Y578083D01*
X1608699Y578883D01*
X1608599Y579817D01*
X1608699Y580750D01*
X1609099Y581550D01*
X1609699Y582217D01*
X1610499Y582483D01*
X1611199Y582350D01*
X1611699Y582083D01*
X1612199Y581550D01*
G01X1616999Y577150D02*
Y582483D01*
G01Y581417D02*
X1617499Y581950D01*
X1617999Y582350D01*
X1618699Y582483D01*
X1619199Y582350D01*
X1619799Y581950D01*
G01X1628199Y577150D02*
Y582483D01*
G01Y581550D02*
X1627799Y582083D01*
X1627199Y582350D01*
X1626499Y582483D01*
X1625799Y582217D01*
X1625199Y581683D01*
X1624799Y580883D01*
X1624599Y579817D01*
X1624799Y578750D01*
X1625199Y577950D01*
X1625799Y577417D01*
X1626499Y577150D01*
X1627199Y577283D01*
X1627799Y577683D01*
X1628199Y578216D01*
G01X1631899Y582483D02*
X1633099Y577150D01*
X1634399Y582483D01*
X1635699Y577150D01*
X1636899Y582483D01*
G01X1642399D02*
Y577150D01*
G01Y584617D02*
X1642199Y584750D01*
Y585017D01*
X1642399Y585150D01*
X1642599Y585017D01*
Y584750D01*
X1642399Y584617D01*
G01X1648699Y577150D02*
Y582483D01*
G01Y581150D02*
X1649099Y581817D01*
X1649699Y582350D01*
X1650499Y582483D01*
X1651199Y582350D01*
X1651799Y581817D01*
X1652099Y580883D01*
Y577150D01*
G01X1656999Y575150D02*
X1657699Y574617D01*
X1658499Y574483D01*
X1659199Y574617D01*
X1659799Y575283D01*
X1660199Y576217D01*
Y582483D01*
G01Y581417D02*
X1659799Y581950D01*
X1659199Y582350D01*
X1658499Y582483D01*
X1657699Y582217D01*
X1657199Y581683D01*
X1656799Y580750D01*
X1656599Y579817D01*
X1656699Y579017D01*
X1657099Y578083D01*
X1657699Y577417D01*
X1658499Y577150D01*
X1659099Y577283D01*
X1659799Y577817D01*
X1660199Y578350D01*
G01X1665699Y574750D02*
X1667099Y576617D01*
Y578483D01*
X1665699D01*
Y576617D01*
X1667099D01*
G01Y579817D02*
Y581683D01*
X1665699D01*
Y579817D01*
X1667099D01*
G01X800399Y572850D02*
X802799D01*
G01X801599D02*
Y564850D01*
G01X800399D02*
X802799D01*
G01X808999D02*
Y571650D01*
X809199Y572317D01*
X809599Y572717D01*
X810199Y572850D01*
X810799Y572583D01*
X811099Y571917D01*
G01X809899Y569650D02*
X807899D01*
G01X825599Y570183D02*
Y564850D01*
G01Y572317D02*
X825399Y572450D01*
Y572717D01*
X825599Y572850D01*
X825799Y572717D01*
Y572450D01*
X825599Y572317D01*
G01X832099Y565783D02*
X832599Y565250D01*
X833299Y564850D01*
X833899D01*
X834499Y565117D01*
X834899Y565517D01*
X835099Y566050D01*
X834999Y566850D01*
X834599Y567250D01*
X832799Y568050D01*
X832399Y568983D01*
X832599Y569650D01*
X832999Y570050D01*
X833599Y570183D01*
X834199Y570050D01*
X834799Y569650D01*
G01X848199Y562850D02*
X848899Y562317D01*
X849699Y562183D01*
X850399Y562317D01*
X850999Y562983D01*
X851399Y563917D01*
Y570183D01*
G01Y569117D02*
X850999Y569650D01*
X850399Y570050D01*
X849699Y570183D01*
X848899Y569917D01*
X848399Y569383D01*
X847999Y568450D01*
X847799Y567517D01*
X847899Y566717D01*
X848299Y565783D01*
X848899Y565117D01*
X849699Y564850D01*
X850299Y564983D01*
X850999Y565517D01*
X851399Y566050D01*
G01X856199Y564850D02*
Y570183D01*
G01Y569117D02*
X856699Y569650D01*
X857199Y570050D01*
X857899Y570183D01*
X858399Y570050D01*
X858999Y569650D01*
G01X864099Y568450D02*
X867299D01*
X866999Y569383D01*
X866499Y569917D01*
X865799Y570183D01*
X865099Y570050D01*
X864499Y569650D01*
X864099Y568717D01*
X863899Y567916D01*
Y567117D01*
X864099Y566317D01*
X864599Y565517D01*
X865199Y564983D01*
X865899Y564850D01*
X866599Y565117D01*
X867299Y565916D01*
G01X875399Y564850D02*
Y570183D01*
G01Y569250D02*
X874999Y569783D01*
X874399Y570050D01*
X873699Y570183D01*
X872999Y569917D01*
X872399Y569383D01*
X871999Y568583D01*
X871799Y567517D01*
X871999Y566450D01*
X872399Y565650D01*
X872999Y565117D01*
X873699Y564850D01*
X874399Y564983D01*
X874999Y565383D01*
X875399Y565916D01*
G01X881599Y572850D02*
Y564850D01*
G01X880199Y570183D02*
X882999D01*
G01X888099Y568450D02*
X891299D01*
X890999Y569383D01*
X890499Y569917D01*
X889799Y570183D01*
X889099Y570050D01*
X888499Y569650D01*
X888099Y568717D01*
X887899Y567916D01*
Y567117D01*
X888099Y566317D01*
X888599Y565517D01*
X889199Y564983D01*
X889899Y564850D01*
X890599Y565117D01*
X891299Y565916D01*
G01X896199Y564850D02*
Y570183D01*
G01Y569117D02*
X896699Y569650D01*
X897199Y570050D01*
X897899Y570183D01*
X898399Y570050D01*
X898999Y569650D01*
G01X913599Y572850D02*
Y564850D01*
G01X912199Y570183D02*
X914999D01*
G01X919899Y564850D02*
Y572850D01*
G01Y568983D02*
X920399Y569650D01*
X920899Y570050D01*
X921699Y570183D01*
X922299Y570050D01*
X922999Y569517D01*
X923299Y568717D01*
Y564850D01*
G01X931399D02*
Y570183D01*
G01Y569250D02*
X930999Y569783D01*
X930399Y570050D01*
X929699Y570183D01*
X928999Y569917D01*
X928399Y569383D01*
X927999Y568583D01*
X927799Y567517D01*
X927999Y566450D01*
X928399Y565650D01*
X928999Y565117D01*
X929699Y564850D01*
X930399Y564983D01*
X930999Y565383D01*
X931399Y565916D01*
G01X935899Y564850D02*
Y570183D01*
G01Y568850D02*
X936299Y569517D01*
X936899Y570050D01*
X937699Y570183D01*
X938399Y570050D01*
X938999Y569517D01*
X939299Y568583D01*
Y564850D01*
G01X953599D02*
Y572850D01*
X952399Y571250D01*
G01Y564850D02*
X954799D01*
G01X966599D02*
Y570183D01*
G01Y568717D02*
X966899Y569383D01*
X967399Y569917D01*
X968099Y570183D01*
X968799Y569917D01*
X969299Y569383D01*
X969599Y568717D01*
Y564850D01*
G01Y568717D02*
X969899Y569383D01*
X970399Y569917D01*
X971099Y570183D01*
X971799Y569917D01*
X972299Y569383D01*
X972599Y568583D01*
Y564850D01*
G01X977599Y570183D02*
Y564850D01*
G01Y572317D02*
X977399Y572450D01*
Y572717D01*
X977599Y572850D01*
X977799Y572717D01*
Y572450D01*
X977599Y572317D01*
G01X984099Y565783D02*
X984599Y565250D01*
X985299Y564850D01*
X985899D01*
X986499Y565117D01*
X986899Y565517D01*
X987099Y566050D01*
X986999Y566850D01*
X986599Y567250D01*
X984799Y568050D01*
X984399Y568983D01*
X984599Y569650D01*
X984999Y570050D01*
X985599Y570183D01*
X986199Y570050D01*
X986799Y569650D01*
G01X993399Y563383D02*
X993799Y565117D01*
G01X1007799Y562183D02*
Y570183D01*
G01Y568983D02*
X1008299Y569650D01*
X1008799Y570050D01*
X1009599Y570183D01*
X1010299Y570050D01*
X1010999Y569383D01*
X1011299Y568450D01*
X1011399Y567517D01*
X1011299Y566583D01*
X1010999Y565650D01*
X1010399Y565117D01*
X1009599Y564850D01*
X1008899Y564983D01*
X1008199Y565383D01*
X1007799Y565916D01*
G01X1017599Y564850D02*
Y572850D01*
G01X1024099Y568450D02*
X1027299D01*
X1026999Y569383D01*
X1026499Y569917D01*
X1025799Y570183D01*
X1025099Y570050D01*
X1024499Y569650D01*
X1024099Y568717D01*
X1023899Y567916D01*
Y567117D01*
X1024099Y566317D01*
X1024599Y565517D01*
X1025199Y564983D01*
X1025899Y564850D01*
X1026599Y565117D01*
X1027299Y565916D01*
G01X1035399Y564850D02*
Y570183D01*
G01Y569250D02*
X1034999Y569783D01*
X1034399Y570050D01*
X1033699Y570183D01*
X1032999Y569917D01*
X1032399Y569383D01*
X1031999Y568583D01*
X1031799Y567517D01*
X1031999Y566450D01*
X1032399Y565650D01*
X1032999Y565117D01*
X1033699Y564850D01*
X1034399Y564983D01*
X1034999Y565383D01*
X1035399Y565916D01*
G01X1040099Y565783D02*
X1040599Y565250D01*
X1041299Y564850D01*
X1041899D01*
X1042499Y565117D01*
X1042899Y565517D01*
X1043099Y566050D01*
X1042999Y566850D01*
X1042599Y567250D01*
X1040799Y568050D01*
X1040399Y568983D01*
X1040599Y569650D01*
X1040999Y570050D01*
X1041599Y570183D01*
X1042199Y570050D01*
X1042799Y569650D01*
G01X1048099Y568450D02*
X1051299D01*
X1050999Y569383D01*
X1050499Y569917D01*
X1049799Y570183D01*
X1049099Y570050D01*
X1048499Y569650D01*
X1048099Y568717D01*
X1047899Y567916D01*
Y567117D01*
X1048099Y566317D01*
X1048599Y565517D01*
X1049199Y564983D01*
X1049899Y564850D01*
X1050599Y565117D01*
X1051299Y565916D01*
G01X1065599Y570183D02*
Y564850D01*
G01Y572317D02*
X1065399Y572450D01*
Y572717D01*
X1065599Y572850D01*
X1065799Y572717D01*
Y572450D01*
X1065599Y572317D01*
G01X1072099Y565783D02*
X1072599Y565250D01*
X1073299Y564850D01*
X1073899D01*
X1074499Y565117D01*
X1074899Y565517D01*
X1075099Y566050D01*
X1074999Y566850D01*
X1074599Y567250D01*
X1072799Y568050D01*
X1072399Y568983D01*
X1072599Y569650D01*
X1072999Y570050D01*
X1073599Y570183D01*
X1074199Y570050D01*
X1074799Y569650D01*
G01X1080099Y565783D02*
X1080599Y565250D01*
X1081299Y564850D01*
X1081899D01*
X1082499Y565117D01*
X1082899Y565517D01*
X1083099Y566050D01*
X1082999Y566850D01*
X1082599Y567250D01*
X1080799Y568050D01*
X1080399Y568983D01*
X1080599Y569650D01*
X1080999Y570050D01*
X1081599Y570183D01*
X1082199Y570050D01*
X1082799Y569650D01*
G01X1087899Y570183D02*
Y566450D01*
X1088299Y565517D01*
X1088899Y564983D01*
X1089599Y564850D01*
X1090299Y564983D01*
X1090899Y565517D01*
X1091299Y566450D01*
G01Y564850D02*
Y570183D01*
G01X1096099Y568450D02*
X1099299D01*
X1098999Y569383D01*
X1098499Y569917D01*
X1097799Y570183D01*
X1097099Y570050D01*
X1096499Y569650D01*
X1096099Y568717D01*
X1095899Y567916D01*
Y567117D01*
X1096099Y566317D01*
X1096599Y565517D01*
X1097199Y564983D01*
X1097899Y564850D01*
X1098599Y565117D01*
X1099299Y565916D01*
G01X1112099Y568450D02*
X1115299D01*
X1114999Y569383D01*
X1114499Y569917D01*
X1113799Y570183D01*
X1113099Y570050D01*
X1112499Y569650D01*
X1112099Y568717D01*
X1111899Y567916D01*
Y567117D01*
X1112099Y566317D01*
X1112599Y565517D01*
X1113199Y564983D01*
X1113899Y564850D01*
X1114599Y565117D01*
X1115299Y565916D01*
G01X1119899Y564850D02*
Y570183D01*
G01Y568850D02*
X1120299Y569517D01*
X1120899Y570050D01*
X1121699Y570183D01*
X1122399Y570050D01*
X1122999Y569517D01*
X1123299Y568583D01*
Y564850D01*
G01X1128199Y562850D02*
X1128899Y562317D01*
X1129699Y562183D01*
X1130399Y562317D01*
X1130999Y562983D01*
X1131399Y563917D01*
Y570183D01*
G01Y569117D02*
X1130999Y569650D01*
X1130399Y570050D01*
X1129699Y570183D01*
X1128899Y569917D01*
X1128399Y569383D01*
X1127999Y568450D01*
X1127799Y567517D01*
X1127899Y566717D01*
X1128299Y565783D01*
X1128899Y565117D01*
X1129699Y564850D01*
X1130299Y564983D01*
X1130999Y565517D01*
X1131399Y566050D01*
G01X1137599Y570183D02*
Y564850D01*
G01Y572317D02*
X1137399Y572450D01*
Y572717D01*
X1137599Y572850D01*
X1137799Y572717D01*
Y572450D01*
X1137599Y572317D01*
G01X1143899Y564850D02*
Y570183D01*
G01Y568850D02*
X1144299Y569517D01*
X1144899Y570050D01*
X1145699Y570183D01*
X1146399Y570050D01*
X1146999Y569517D01*
X1147299Y568583D01*
Y564850D01*
G01X1152099Y568450D02*
X1155299D01*
X1154999Y569383D01*
X1154499Y569917D01*
X1153799Y570183D01*
X1153099Y570050D01*
X1152499Y569650D01*
X1152099Y568717D01*
X1151899Y567916D01*
Y567117D01*
X1152099Y566317D01*
X1152599Y565517D01*
X1153199Y564983D01*
X1153899Y564850D01*
X1154599Y565117D01*
X1155299Y565916D01*
G01X1160099Y568450D02*
X1163299D01*
X1162999Y569383D01*
X1162499Y569917D01*
X1161799Y570183D01*
X1161099Y570050D01*
X1160499Y569650D01*
X1160099Y568717D01*
X1159899Y567916D01*
Y567117D01*
X1160099Y566317D01*
X1160599Y565517D01*
X1161199Y564983D01*
X1161899Y564850D01*
X1162599Y565117D01*
X1163299Y565916D01*
G01X1168199Y564850D02*
Y570183D01*
G01Y569117D02*
X1168699Y569650D01*
X1169199Y570050D01*
X1169899Y570183D01*
X1170399Y570050D01*
X1170999Y569650D01*
G01X1177599Y570183D02*
Y564850D01*
G01Y572317D02*
X1177399Y572450D01*
Y572717D01*
X1177599Y572850D01*
X1177799Y572717D01*
Y572450D01*
X1177599Y572317D01*
G01X1183899Y564850D02*
Y570183D01*
G01Y568850D02*
X1184299Y569517D01*
X1184899Y570050D01*
X1185699Y570183D01*
X1186399Y570050D01*
X1186999Y569517D01*
X1187299Y568583D01*
Y564850D01*
G01X1192199Y562850D02*
X1192899Y562317D01*
X1193699Y562183D01*
X1194399Y562317D01*
X1194999Y562983D01*
X1195399Y563917D01*
Y570183D01*
G01Y569117D02*
X1194999Y569650D01*
X1194399Y570050D01*
X1193699Y570183D01*
X1192899Y569917D01*
X1192399Y569383D01*
X1191999Y568450D01*
X1191799Y567517D01*
X1191899Y566717D01*
X1192299Y565783D01*
X1192899Y565117D01*
X1193699Y564850D01*
X1194299Y564983D01*
X1194999Y565517D01*
X1195399Y566050D01*
G01X1211399Y562183D02*
Y570183D01*
G01Y568983D02*
X1210899Y569650D01*
X1210299Y570050D01*
X1209599Y570183D01*
X1208999Y570050D01*
X1208299Y569383D01*
X1207899Y568450D01*
X1207799Y567517D01*
X1207899Y566583D01*
X1208299Y565650D01*
X1208999Y564983D01*
X1209599Y564850D01*
X1210299Y564983D01*
X1210899Y565383D01*
X1211399Y566050D01*
G01X1215899Y570183D02*
Y566450D01*
X1216299Y565517D01*
X1216899Y564983D01*
X1217599Y564850D01*
X1218299Y564983D01*
X1218899Y565517D01*
X1219299Y566450D01*
G01Y564850D02*
Y570183D01*
G01X1224099Y568450D02*
X1227299D01*
X1226999Y569383D01*
X1226499Y569917D01*
X1225799Y570183D01*
X1225099Y570050D01*
X1224499Y569650D01*
X1224099Y568717D01*
X1223899Y567916D01*
Y567117D01*
X1224099Y566317D01*
X1224599Y565517D01*
X1225199Y564983D01*
X1225899Y564850D01*
X1226599Y565117D01*
X1227299Y565916D01*
G01X1232199Y564850D02*
Y570183D01*
G01Y569117D02*
X1232699Y569650D01*
X1233199Y570050D01*
X1233899Y570183D01*
X1234399Y570050D01*
X1234999Y569650D01*
G01X1239499Y562450D02*
X1240099Y562183D01*
X1240899Y562450D01*
X1241399Y562983D01*
X1241799Y563650D01*
X1242399Y565783D01*
X1243699Y570183D01*
G01X1240499D02*
X1242399Y565783D01*
G01X1249599Y564583D02*
X1249399Y564717D01*
Y564983D01*
X1249599Y565117D01*
X1249799Y564983D01*
Y564717D01*
X1249599Y564583D01*
G01X799999Y596950D02*
Y591217D01*
X800399Y590016D01*
X801199Y589217D01*
X802199Y588950D01*
X803199Y589217D01*
X803999Y590016D01*
X804399Y591217D01*
Y596950D01*
G01X808499Y588950D02*
Y594283D01*
G01Y592950D02*
X808899Y593617D01*
X809499Y594150D01*
X810299Y594283D01*
X810999Y594150D01*
X811599Y593617D01*
X811899Y592683D01*
Y588950D01*
G01X818199Y594283D02*
Y588950D01*
G01Y596417D02*
X817999Y596550D01*
Y596817D01*
X818199Y596950D01*
X818399Y596817D01*
Y596550D01*
X818199Y596417D01*
G01X826199Y596950D02*
Y588950D01*
G01X824799Y594283D02*
X827599D01*
G01X843799Y593617D02*
X843099Y594150D01*
X842499Y594283D01*
X841699Y594017D01*
X841099Y593483D01*
X840699Y592550D01*
X840599Y591617D01*
X840699Y590683D01*
X841099Y589883D01*
X841699Y589217D01*
X842499Y588950D01*
X843199Y589217D01*
X843799Y589750D01*
G01X850199Y588950D02*
X849599Y589083D01*
X848999Y589617D01*
X848599Y590550D01*
X848399Y591617D01*
X848599Y592683D01*
X848999Y593617D01*
X849599Y594150D01*
X850199Y594283D01*
X850799Y594150D01*
X851399Y593617D01*
X851799Y592683D01*
X851899Y591617D01*
X851799Y590550D01*
X851399Y589617D01*
X850799Y589083D01*
X850199Y588950D01*
G01X856499D02*
Y594283D01*
G01Y592950D02*
X856899Y593617D01*
X857499Y594150D01*
X858299Y594283D01*
X858999Y594150D01*
X859599Y593617D01*
X859899Y592683D01*
Y588950D01*
G01X864399Y594283D02*
X866199Y588950D01*
X867999Y594283D01*
G01X872699Y592550D02*
X875899D01*
X875599Y593483D01*
X875099Y594017D01*
X874399Y594283D01*
X873699Y594150D01*
X873099Y593750D01*
X872699Y592817D01*
X872499Y592016D01*
Y591217D01*
X872699Y590417D01*
X873199Y589617D01*
X873799Y589083D01*
X874499Y588950D01*
X875199Y589217D01*
X875899Y590016D01*
G01X880799Y588950D02*
Y594283D01*
G01Y593217D02*
X881299Y593750D01*
X881799Y594150D01*
X882499Y594283D01*
X882999Y594150D01*
X883599Y593750D01*
G01X888699Y589883D02*
X889199Y589350D01*
X889899Y588950D01*
X890499D01*
X891099Y589217D01*
X891499Y589617D01*
X891699Y590150D01*
X891599Y590950D01*
X891199Y591350D01*
X889399Y592150D01*
X888999Y593083D01*
X889199Y593750D01*
X889599Y594150D01*
X890199Y594283D01*
X890799Y594150D01*
X891399Y593750D01*
G01X898199Y594283D02*
Y588950D01*
G01Y596417D02*
X897999Y596550D01*
Y596817D01*
X898199Y596950D01*
X898399Y596817D01*
Y596550D01*
X898199Y596417D01*
G01X906199Y588950D02*
X905599Y589083D01*
X904999Y589617D01*
X904599Y590550D01*
X904399Y591617D01*
X904599Y592683D01*
X904999Y593617D01*
X905599Y594150D01*
X906199Y594283D01*
X906799Y594150D01*
X907399Y593617D01*
X907799Y592683D01*
X907899Y591617D01*
X907799Y590550D01*
X907399Y589617D01*
X906799Y589083D01*
X906199Y588950D01*
G01X912499D02*
Y594283D01*
G01Y592950D02*
X912899Y593617D01*
X913499Y594150D01*
X914299Y594283D01*
X914999Y594150D01*
X915599Y593617D01*
X915899Y592683D01*
Y588950D01*
G01X930199Y594283D02*
Y588950D01*
G01Y596417D02*
X929999Y596550D01*
Y596817D01*
X930199Y596950D01*
X930399Y596817D01*
Y596550D01*
X930199Y596417D01*
G01X936699Y589883D02*
X937199Y589350D01*
X937899Y588950D01*
X938499D01*
X939099Y589217D01*
X939499Y589617D01*
X939699Y590150D01*
X939599Y590950D01*
X939199Y591350D01*
X937399Y592150D01*
X936999Y593083D01*
X937199Y593750D01*
X937599Y594150D01*
X938199Y594283D01*
X938799Y594150D01*
X939399Y593750D01*
G01X944699Y589883D02*
X945199Y589350D01*
X945899Y588950D01*
X946499D01*
X947099Y589217D01*
X947499Y589617D01*
X947699Y590150D01*
X947599Y590950D01*
X947199Y591350D01*
X945399Y592150D01*
X944999Y593083D01*
X945199Y593750D01*
X945599Y594150D01*
X946199Y594283D01*
X946799Y594150D01*
X947399Y593750D01*
G01X952499Y594283D02*
Y590550D01*
X952899Y589617D01*
X953499Y589083D01*
X954199Y588950D01*
X954899Y589083D01*
X955499Y589617D01*
X955899Y590550D01*
G01Y588950D02*
Y594283D01*
G01X960699Y592550D02*
X963899D01*
X963599Y593483D01*
X963099Y594017D01*
X962399Y594283D01*
X961699Y594150D01*
X961099Y593750D01*
X960699Y592817D01*
X960499Y592016D01*
Y591217D01*
X960699Y590417D01*
X961199Y589617D01*
X961799Y589083D01*
X962499Y588950D01*
X963199Y589217D01*
X963899Y590016D01*
G01X970199Y588683D02*
X969999Y588817D01*
Y589083D01*
X970199Y589217D01*
X970399Y589083D01*
Y588817D01*
X970199Y588683D01*
G01Y592283D02*
X969999Y592417D01*
Y592683D01*
X970199Y592817D01*
X970399Y592683D01*
Y592417D01*
X970199Y592283D01*
G01X801399Y794350D02*
Y802350D01*
X805999Y794350D01*
Y802350D01*
G01X811699Y794350D02*
X810899Y794483D01*
X810199Y795017D01*
X809599Y795817D01*
X809199Y796750D01*
X808999Y797817D01*
Y798883D01*
X809199Y799950D01*
X809599Y800883D01*
X810199Y801683D01*
X810899Y802217D01*
X811699Y802350D01*
X812499Y802217D01*
X813199Y801683D01*
X813799Y800883D01*
X814199Y799950D01*
X814399Y798883D01*
Y797817D01*
X814199Y796750D01*
X813799Y795817D01*
X813199Y795017D01*
X812499Y794483D01*
X811699Y794350D01*
G01X819699Y794083D02*
X819499Y794217D01*
Y794483D01*
X819699Y794617D01*
X819899Y794483D01*
Y794217D01*
X819699Y794083D01*
G01X806199Y628350D02*
Y636350D01*
X804999Y634750D01*
G01Y628350D02*
X807399D01*
G01X814199D02*
Y636350D01*
X812999Y634750D01*
G01Y628350D02*
X815399D01*
G01X805699Y640850D02*
Y648850D01*
X804499Y647250D01*
G01Y640850D02*
X806899D01*
G01X813699Y648850D02*
X812899Y648583D01*
X812299Y647917D01*
X811899Y647117D01*
X811599Y646050D01*
X811499Y644850D01*
X811599Y643650D01*
X811899Y642583D01*
X812299Y641783D01*
X812899Y641117D01*
X813699Y640850D01*
X814499Y641117D01*
X815099Y641783D01*
X815499Y642583D01*
X815799Y643650D01*
X815899Y644850D01*
X815799Y646050D01*
X815499Y647117D01*
X815099Y647917D01*
X814499Y648583D01*
X813699Y648850D01*
G01X808499Y654783D02*
X809199Y654117D01*
X809999Y653850D01*
X810799Y654117D01*
X811499Y654916D01*
X811999Y656117D01*
X812199Y657317D01*
Y658783D01*
X811999Y659983D01*
X811499Y661050D01*
X810899Y661583D01*
X810199Y661850D01*
X809399Y661583D01*
X808799Y661050D01*
X808399Y660250D01*
X808199Y659183D01*
X808399Y658250D01*
X808899Y657317D01*
X809499Y656783D01*
X810199Y656650D01*
X810999Y656916D01*
X811599Y657583D01*
X812199Y658783D01*
G01X810199Y666350D02*
X810899Y666483D01*
X811699Y666883D01*
X812199Y667550D01*
X812399Y668483D01*
X812199Y669416D01*
X811599Y670217D01*
X810699Y670617D01*
X809699D01*
X809099Y670883D01*
X808599Y671550D01*
X808399Y672483D01*
X808699Y673417D01*
X809399Y674083D01*
X810199Y674350D01*
X810999Y674083D01*
X811699Y673417D01*
X811999Y672483D01*
X811799Y671550D01*
X811299Y670883D01*
X810699Y670617D01*
X809699D01*
X808799Y670217D01*
X808199Y669416D01*
X807999Y668483D01*
X808199Y667550D01*
X808699Y666883D01*
X809499Y666483D01*
X810199Y666350D01*
G01X809999Y678350D02*
X810199Y680083D01*
X810499Y681550D01*
X810899Y682883D01*
X811399Y684350D01*
X812199Y686350D01*
X808199D01*
G01X808799Y694683D02*
X809499Y695617D01*
X810099Y696150D01*
X810899Y696417D01*
X811599Y696150D01*
X812099Y695617D01*
X812499Y694817D01*
X812599Y693883D01*
X812499Y693083D01*
X812099Y692283D01*
X811499Y691617D01*
X810799Y691350D01*
X809999Y691617D01*
X809299Y692416D01*
X808899Y693617D01*
X808799Y694950D01*
X808999Y696683D01*
X809299Y697617D01*
X809799Y698550D01*
X810499Y699217D01*
X811199Y699350D01*
X811899Y699083D01*
X812399Y698417D01*
G01X811899Y729350D02*
Y737350D01*
X808199Y731617D01*
X813199D01*
G01X808499Y712050D02*
X809099Y711383D01*
X809799Y710983D01*
X810699Y710850D01*
X811599Y711117D01*
X812299Y711650D01*
X812799Y712583D01*
X812899Y713650D01*
X812699Y714717D01*
X812199Y715383D01*
X811499Y715917D01*
X810799Y716050D01*
X810099Y715917D01*
X809199Y715383D01*
X809499Y718850D01*
X812199D01*
G01X808499Y754950D02*
X809099Y754017D01*
X809899Y753483D01*
X810799Y753350D01*
X811599Y753483D01*
X812399Y754150D01*
X812899Y754950D01*
X812999Y755750D01*
X812799Y756683D01*
X812099Y757350D01*
X811399Y757617D01*
X810499D01*
G01X811399D02*
X811999Y758017D01*
X812499Y758683D01*
X812699Y759483D01*
X812499Y760283D01*
X811999Y760950D01*
X811099Y761350D01*
X810199Y761217D01*
X809299Y760683D01*
G01Y773017D02*
X809899Y773817D01*
X810599Y774217D01*
X811399Y774350D01*
X812399Y774083D01*
X813099Y773417D01*
X813299Y772617D01*
X813199Y771816D01*
X812799Y771150D01*
X810799Y769817D01*
X809899Y768883D01*
X809299Y767550D01*
X809099Y766350D01*
X813299D01*
G01X811199Y778850D02*
Y786850D01*
X809999Y785250D01*
G01Y778850D02*
X812399D01*
G01X843199Y628850D02*
Y636850D01*
X845699D01*
X846499Y636450D01*
X846999Y635917D01*
X847199Y634850D01*
X846999Y633783D01*
X846399Y633117D01*
X845699Y632717D01*
X843199D01*
G01X845699D02*
X847199Y628850D01*
G01X853199D02*
X852599Y628983D01*
X851999Y629517D01*
X851599Y630450D01*
X851399Y631517D01*
X851599Y632583D01*
X851999Y633517D01*
X852599Y634050D01*
X853199Y634183D01*
X853799Y634050D01*
X854399Y633517D01*
X854799Y632583D01*
X854899Y631517D01*
X854799Y630450D01*
X854399Y629517D01*
X853799Y628983D01*
X853199Y628850D01*
G01X859499Y634183D02*
Y630450D01*
X859899Y629517D01*
X860499Y628983D01*
X861199Y628850D01*
X861899Y628983D01*
X862499Y629517D01*
X862899Y630450D01*
G01Y628850D02*
Y634183D01*
G01X867799Y626850D02*
X868499Y626317D01*
X869299Y626183D01*
X869999Y626317D01*
X870599Y626983D01*
X870999Y627917D01*
Y634183D01*
G01Y633117D02*
X870599Y633650D01*
X869999Y634050D01*
X869299Y634183D01*
X868499Y633917D01*
X867999Y633383D01*
X867599Y632450D01*
X867399Y631517D01*
X867499Y630717D01*
X867899Y629783D01*
X868499Y629117D01*
X869299Y628850D01*
X869899Y628983D01*
X870599Y629517D01*
X870999Y630050D01*
G01X875499Y628850D02*
Y636850D01*
G01Y632983D02*
X875999Y633650D01*
X876499Y634050D01*
X877299Y634183D01*
X877899Y634050D01*
X878599Y633517D01*
X878899Y632717D01*
Y628850D01*
G01X883499D02*
Y634183D01*
G01Y632850D02*
X883899Y633517D01*
X884499Y634050D01*
X885299Y634183D01*
X885999Y634050D01*
X886599Y633517D01*
X886899Y632583D01*
Y628850D01*
G01X891699Y632450D02*
X894899D01*
X894599Y633383D01*
X894099Y633917D01*
X893399Y634183D01*
X892699Y634050D01*
X892099Y633650D01*
X891699Y632717D01*
X891499Y631916D01*
Y631117D01*
X891699Y630317D01*
X892199Y629517D01*
X892799Y628983D01*
X893499Y628850D01*
X894199Y629117D01*
X894899Y629916D01*
G01X899699Y629783D02*
X900199Y629250D01*
X900899Y628850D01*
X901499D01*
X902099Y629117D01*
X902499Y629517D01*
X902699Y630050D01*
X902599Y630850D01*
X902199Y631250D01*
X900399Y632050D01*
X899999Y632983D01*
X900199Y633650D01*
X900599Y634050D01*
X901199Y634183D01*
X901799Y634050D01*
X902399Y633650D01*
G01X907699Y629783D02*
X908199Y629250D01*
X908899Y628850D01*
X909499D01*
X910099Y629117D01*
X910499Y629517D01*
X910699Y630050D01*
X910599Y630850D01*
X910199Y631250D01*
X908399Y632050D01*
X907999Y632983D01*
X908199Y633650D01*
X908599Y634050D01*
X909199Y634183D01*
X909799Y634050D01*
X910399Y633650D01*
G01X839599Y720850D02*
Y728850D01*
G01X843799D02*
Y720850D01*
G01Y724850D02*
X839599D01*
G01X849699Y720850D02*
X849099Y720983D01*
X848499Y721517D01*
X848099Y722450D01*
X847899Y723517D01*
X848099Y724583D01*
X848499Y725517D01*
X849099Y726050D01*
X849699Y726183D01*
X850299Y726050D01*
X850899Y725517D01*
X851299Y724583D01*
X851399Y723517D01*
X851299Y722450D01*
X850899Y721517D01*
X850299Y720983D01*
X849699Y720850D01*
G01X857699D02*
Y728850D01*
G01X864199Y724450D02*
X867399D01*
X867099Y725383D01*
X866599Y725917D01*
X865899Y726183D01*
X865199Y726050D01*
X864599Y725650D01*
X864199Y724717D01*
X863999Y723916D01*
Y723117D01*
X864199Y722317D01*
X864699Y721517D01*
X865299Y720983D01*
X865999Y720850D01*
X866699Y721117D01*
X867399Y721916D01*
G01X827599Y778350D02*
Y786350D01*
G01X831799D02*
Y778350D01*
G01Y782350D02*
X827599D01*
G01X837699Y778350D02*
X837099Y778483D01*
X836499Y779017D01*
X836099Y779950D01*
X835899Y781017D01*
X836099Y782083D01*
X836499Y783017D01*
X837099Y783550D01*
X837699Y783683D01*
X838299Y783550D01*
X838899Y783017D01*
X839299Y782083D01*
X839399Y781017D01*
X839299Y779950D01*
X838899Y779017D01*
X838299Y778483D01*
X837699Y778350D01*
G01X845699D02*
Y786350D01*
G01X852199Y781950D02*
X855399D01*
X855099Y782883D01*
X854599Y783417D01*
X853899Y783683D01*
X853199Y783550D01*
X852599Y783150D01*
X852199Y782217D01*
X851999Y781416D01*
Y780617D01*
X852199Y779817D01*
X852699Y779017D01*
X853299Y778483D01*
X853999Y778350D01*
X854699Y778617D01*
X855399Y779416D01*
G01X857899Y538450D02*
Y530450D01*
G01X855599Y538450D02*
X860199D01*
G01X864199Y530450D02*
Y538450D01*
G01Y534583D02*
X864699Y535250D01*
X865199Y535650D01*
X865999Y535783D01*
X866599Y535650D01*
X867299Y535117D01*
X867599Y534317D01*
Y530450D01*
G01X872399Y534050D02*
X875599D01*
X875299Y534983D01*
X874799Y535517D01*
X874099Y535783D01*
X873399Y535650D01*
X872799Y535250D01*
X872399Y534317D01*
X872199Y533516D01*
Y532717D01*
X872399Y531917D01*
X872899Y531117D01*
X873499Y530583D01*
X874199Y530450D01*
X874899Y530717D01*
X875599Y531516D01*
G01X880499Y530450D02*
Y535783D01*
G01Y534717D02*
X880999Y535250D01*
X881499Y535650D01*
X882199Y535783D01*
X882699Y535650D01*
X883299Y535250D01*
G01X888399Y534050D02*
X891599D01*
X891299Y534983D01*
X890799Y535517D01*
X890099Y535783D01*
X889399Y535650D01*
X888799Y535250D01*
X888399Y534317D01*
X888199Y533516D01*
Y532717D01*
X888399Y531917D01*
X888899Y531117D01*
X889499Y530583D01*
X890199Y530450D01*
X890899Y530717D01*
X891599Y531516D01*
G01X897299Y530450D02*
Y537250D01*
X897499Y537917D01*
X897899Y538317D01*
X898499Y538450D01*
X899099Y538183D01*
X899399Y537517D01*
G01X898199Y535250D02*
X896199D01*
G01X905899Y530450D02*
X905299Y530583D01*
X904699Y531117D01*
X904299Y532050D01*
X904099Y533117D01*
X904299Y534183D01*
X904699Y535117D01*
X905299Y535650D01*
X905899Y535783D01*
X906499Y535650D01*
X907099Y535117D01*
X907499Y534183D01*
X907599Y533117D01*
X907499Y532050D01*
X907099Y531117D01*
X906499Y530583D01*
X905899Y530450D01*
G01X912499D02*
Y535783D01*
G01Y534717D02*
X912999Y535250D01*
X913499Y535650D01*
X914199Y535783D01*
X914699Y535650D01*
X915299Y535250D01*
G01X920399Y534050D02*
X923599D01*
X923299Y534983D01*
X922799Y535517D01*
X922099Y535783D01*
X921399Y535650D01*
X920799Y535250D01*
X920399Y534317D01*
X920199Y533516D01*
Y532717D01*
X920399Y531917D01*
X920899Y531117D01*
X921499Y530583D01*
X922199Y530450D01*
X922899Y530717D01*
X923599Y531516D01*
G01X929699Y528983D02*
X930099Y530717D01*
G01X944099Y527783D02*
Y535783D01*
G01Y534583D02*
X944599Y535250D01*
X945099Y535650D01*
X945899Y535783D01*
X946599Y535650D01*
X947299Y534983D01*
X947599Y534050D01*
X947699Y533117D01*
X947599Y532183D01*
X947299Y531250D01*
X946699Y530717D01*
X945899Y530450D01*
X945199Y530583D01*
X944499Y530983D01*
X944099Y531516D01*
G01X953899Y530450D02*
Y538450D01*
G01X960399Y534050D02*
X963599D01*
X963299Y534983D01*
X962799Y535517D01*
X962099Y535783D01*
X961399Y535650D01*
X960799Y535250D01*
X960399Y534317D01*
X960199Y533516D01*
Y532717D01*
X960399Y531917D01*
X960899Y531117D01*
X961499Y530583D01*
X962199Y530450D01*
X962899Y530717D01*
X963599Y531516D01*
G01X971699Y530450D02*
Y535783D01*
G01Y534850D02*
X971299Y535383D01*
X970699Y535650D01*
X969999Y535783D01*
X969299Y535517D01*
X968699Y534983D01*
X968299Y534183D01*
X968099Y533117D01*
X968299Y532050D01*
X968699Y531250D01*
X969299Y530717D01*
X969999Y530450D01*
X970699Y530583D01*
X971299Y530983D01*
X971699Y531516D01*
G01X976399Y531383D02*
X976899Y530850D01*
X977599Y530450D01*
X978199D01*
X978799Y530717D01*
X979199Y531117D01*
X979399Y531650D01*
X979299Y532450D01*
X978899Y532850D01*
X977099Y533650D01*
X976699Y534583D01*
X976899Y535250D01*
X977299Y535650D01*
X977899Y535783D01*
X978499Y535650D01*
X979099Y535250D01*
G01X984399Y534050D02*
X987599D01*
X987299Y534983D01*
X986799Y535517D01*
X986099Y535783D01*
X985399Y535650D01*
X984799Y535250D01*
X984399Y534317D01*
X984199Y533516D01*
Y532717D01*
X984399Y531917D01*
X984899Y531117D01*
X985499Y530583D01*
X986199Y530450D01*
X986899Y530717D01*
X987599Y531516D01*
G01X1001299Y530450D02*
Y537250D01*
X1001499Y537917D01*
X1001899Y538317D01*
X1002499Y538450D01*
X1003099Y538183D01*
X1003399Y537517D01*
G01X1002199Y535250D02*
X1000199D01*
G01X1009899Y530450D02*
X1009299Y530583D01*
X1008699Y531117D01*
X1008299Y532050D01*
X1008099Y533117D01*
X1008299Y534183D01*
X1008699Y535117D01*
X1009299Y535650D01*
X1009899Y535783D01*
X1010499Y535650D01*
X1011099Y535117D01*
X1011499Y534183D01*
X1011599Y533117D01*
X1011499Y532050D01*
X1011099Y531117D01*
X1010499Y530583D01*
X1009899Y530450D01*
G01X1017899D02*
Y538450D01*
G01X1025899Y530450D02*
Y538450D01*
G01X1033899Y530450D02*
X1033299Y530583D01*
X1032699Y531117D01*
X1032299Y532050D01*
X1032099Y533117D01*
X1032299Y534183D01*
X1032699Y535117D01*
X1033299Y535650D01*
X1033899Y535783D01*
X1034499Y535650D01*
X1035099Y535117D01*
X1035499Y534183D01*
X1035599Y533117D01*
X1035499Y532050D01*
X1035099Y531117D01*
X1034499Y530583D01*
X1033899Y530450D01*
G01X1039399Y535783D02*
X1040599Y530450D01*
X1041899Y535783D01*
X1043199Y530450D01*
X1044399Y535783D01*
G01X1055699Y532050D02*
X1056299Y531117D01*
X1057099Y530583D01*
X1057999Y530450D01*
X1058799Y530583D01*
X1059599Y531250D01*
X1060099Y532050D01*
X1060199Y532850D01*
X1059999Y533783D01*
X1059299Y534450D01*
X1058599Y534717D01*
X1057699D01*
G01X1058599D02*
X1059199Y535117D01*
X1059699Y535783D01*
X1059899Y536583D01*
X1059699Y537383D01*
X1059199Y538050D01*
X1058299Y538450D01*
X1057399Y538317D01*
X1056499Y537783D01*
G01X1065899Y530183D02*
X1065699Y530317D01*
Y530583D01*
X1065899Y530717D01*
X1066099Y530583D01*
Y530317D01*
X1065899Y530183D01*
G01X1073899Y530450D02*
Y538450D01*
X1072699Y536850D01*
G01Y530450D02*
X1075099D01*
G01X1081899D02*
X1082599Y530583D01*
X1083399Y530983D01*
X1083899Y531650D01*
X1084099Y532583D01*
X1083899Y533516D01*
X1083299Y534317D01*
X1082399Y534717D01*
X1081399D01*
X1080799Y534983D01*
X1080299Y535650D01*
X1080099Y536583D01*
X1080399Y537517D01*
X1081099Y538183D01*
X1081899Y538450D01*
X1082699Y538183D01*
X1083399Y537517D01*
X1083699Y536583D01*
X1083499Y535650D01*
X1082999Y534983D01*
X1082399Y534717D01*
X1081399D01*
X1080499Y534317D01*
X1079899Y533516D01*
X1079699Y532583D01*
X1079899Y531650D01*
X1080399Y530983D01*
X1081199Y530583D01*
X1081899Y530450D01*
G01X1086899D02*
Y535783D01*
G01Y534317D02*
X1087199Y534983D01*
X1087699Y535517D01*
X1088399Y535783D01*
X1089099Y535517D01*
X1089599Y534983D01*
X1089899Y534317D01*
Y530450D01*
G01Y534317D02*
X1090199Y534983D01*
X1090699Y535517D01*
X1091399Y535783D01*
X1092099Y535517D01*
X1092599Y534983D01*
X1092899Y534183D01*
Y530450D01*
G01X1094899D02*
Y535783D01*
G01Y534317D02*
X1095199Y534983D01*
X1095699Y535517D01*
X1096399Y535783D01*
X1097099Y535517D01*
X1097599Y534983D01*
X1097899Y534317D01*
Y530450D01*
G01Y534317D02*
X1098199Y534983D01*
X1098699Y535517D01*
X1099399Y535783D01*
X1100099Y535517D01*
X1100599Y534983D01*
X1100899Y534183D01*
Y530450D01*
G01X1113899Y538450D02*
Y530450D01*
G01X1112499Y535783D02*
X1115299D01*
G01X1121899Y530450D02*
X1121299Y530583D01*
X1120699Y531117D01*
X1120299Y532050D01*
X1120099Y533117D01*
X1120299Y534183D01*
X1120699Y535117D01*
X1121299Y535650D01*
X1121899Y535783D01*
X1122499Y535650D01*
X1123099Y535117D01*
X1123499Y534183D01*
X1123599Y533117D01*
X1123499Y532050D01*
X1123099Y531117D01*
X1122499Y530583D01*
X1121899Y530450D01*
G01X1136099Y527783D02*
Y535783D01*
G01Y534583D02*
X1136599Y535250D01*
X1137099Y535650D01*
X1137899Y535783D01*
X1138599Y535650D01*
X1139299Y534983D01*
X1139599Y534050D01*
X1139699Y533117D01*
X1139599Y532183D01*
X1139299Y531250D01*
X1138699Y530717D01*
X1137899Y530450D01*
X1137199Y530583D01*
X1136499Y530983D01*
X1136099Y531516D01*
G01X1144499Y530450D02*
Y535783D01*
G01Y534717D02*
X1144999Y535250D01*
X1145499Y535650D01*
X1146199Y535783D01*
X1146699Y535650D01*
X1147299Y535250D01*
G01X1153899Y530450D02*
X1153299Y530583D01*
X1152699Y531117D01*
X1152299Y532050D01*
X1152099Y533117D01*
X1152299Y534183D01*
X1152699Y535117D01*
X1153299Y535650D01*
X1153899Y535783D01*
X1154499Y535650D01*
X1155099Y535117D01*
X1155499Y534183D01*
X1155599Y533117D01*
X1155499Y532050D01*
X1155099Y531117D01*
X1154499Y530583D01*
X1153899Y530450D01*
G01X1163699Y538450D02*
Y530450D01*
G01Y531650D02*
X1163299Y530983D01*
X1162699Y530583D01*
X1161999Y530450D01*
X1161199Y530717D01*
X1160599Y531383D01*
X1160199Y532183D01*
X1160099Y533117D01*
X1160199Y534050D01*
X1160599Y534850D01*
X1161199Y535517D01*
X1161999Y535783D01*
X1162699Y535650D01*
X1163199Y535383D01*
X1163699Y534850D01*
G01X1168199Y535783D02*
Y532050D01*
X1168599Y531117D01*
X1169199Y530583D01*
X1169899Y530450D01*
X1170599Y530583D01*
X1171199Y531117D01*
X1171599Y532050D01*
G01Y530450D02*
Y535783D01*
G01X1179499Y535117D02*
X1178799Y535650D01*
X1178199Y535783D01*
X1177399Y535517D01*
X1176799Y534983D01*
X1176399Y534050D01*
X1176299Y533117D01*
X1176399Y532183D01*
X1176799Y531383D01*
X1177399Y530717D01*
X1178199Y530450D01*
X1178899Y530717D01*
X1179499Y531250D01*
G01X1184399Y534050D02*
X1187599D01*
X1187299Y534983D01*
X1186799Y535517D01*
X1186099Y535783D01*
X1185399Y535650D01*
X1184799Y535250D01*
X1184399Y534317D01*
X1184199Y533516D01*
Y532717D01*
X1184399Y531917D01*
X1184899Y531117D01*
X1185499Y530583D01*
X1186199Y530450D01*
X1186899Y530717D01*
X1187599Y531516D01*
G01X1201899Y538450D02*
Y530450D01*
G01X1200499Y535783D02*
X1203299D01*
G01X1208199Y530450D02*
Y538450D01*
G01Y534583D02*
X1208699Y535250D01*
X1209199Y535650D01*
X1209999Y535783D01*
X1210599Y535650D01*
X1211299Y535117D01*
X1211599Y534317D01*
Y530450D01*
G01X1217899Y535783D02*
Y530450D01*
G01Y537917D02*
X1217699Y538050D01*
Y538317D01*
X1217899Y538450D01*
X1218099Y538317D01*
Y538050D01*
X1217899Y537917D01*
G01X1224399Y531383D02*
X1224899Y530850D01*
X1225599Y530450D01*
X1226199D01*
X1226799Y530717D01*
X1227199Y531117D01*
X1227399Y531650D01*
X1227299Y532450D01*
X1226899Y532850D01*
X1225099Y533650D01*
X1224699Y534583D01*
X1224899Y535250D01*
X1225299Y535650D01*
X1225899Y535783D01*
X1226499Y535650D01*
X1227099Y535250D01*
G01X1240099Y530450D02*
Y538450D01*
G01Y534450D02*
X1240599Y535250D01*
X1241199Y535650D01*
X1241799Y535783D01*
X1242699Y535517D01*
X1243299Y534983D01*
X1243699Y534050D01*
Y532983D01*
X1243499Y531917D01*
X1243099Y531117D01*
X1242399Y530583D01*
X1241799Y530450D01*
X1241199Y530583D01*
X1240599Y530983D01*
X1240099Y531650D01*
G01X1249899Y530450D02*
X1249299Y530583D01*
X1248699Y531117D01*
X1248299Y532050D01*
X1248099Y533117D01*
X1248299Y534183D01*
X1248699Y535117D01*
X1249299Y535650D01*
X1249899Y535783D01*
X1250499Y535650D01*
X1251099Y535117D01*
X1251499Y534183D01*
X1251599Y533117D01*
X1251499Y532050D01*
X1251099Y531117D01*
X1250499Y530583D01*
X1249899Y530450D01*
G01X1259699D02*
Y535783D01*
G01Y534850D02*
X1259299Y535383D01*
X1258699Y535650D01*
X1257999Y535783D01*
X1257299Y535517D01*
X1256699Y534983D01*
X1256299Y534183D01*
X1256099Y533117D01*
X1256299Y532050D01*
X1256699Y531250D01*
X1257299Y530717D01*
X1257999Y530450D01*
X1258699Y530583D01*
X1259299Y530983D01*
X1259699Y531516D01*
G01X1264499Y530450D02*
Y535783D01*
G01Y534717D02*
X1264999Y535250D01*
X1265499Y535650D01*
X1266199Y535783D01*
X1266699Y535650D01*
X1267299Y535250D01*
G01X1275699Y538450D02*
Y530450D01*
G01Y531650D02*
X1275299Y530983D01*
X1274699Y530583D01*
X1273999Y530450D01*
X1273199Y530717D01*
X1272599Y531383D01*
X1272199Y532183D01*
X1272099Y533117D01*
X1272199Y534050D01*
X1272599Y534850D01*
X1273199Y535517D01*
X1273999Y535783D01*
X1274699Y535650D01*
X1275199Y535383D01*
X1275699Y534850D01*
G01X1281899Y530183D02*
X1281699Y530317D01*
Y530583D01*
X1281899Y530717D01*
X1282099Y530583D01*
Y530317D01*
X1281899Y530183D01*
G01X857699Y548450D02*
Y540450D01*
G01X855399Y548450D02*
X859999D01*
G01X863999Y540450D02*
Y548450D01*
G01Y544583D02*
X864499Y545250D01*
X864999Y545650D01*
X865799Y545783D01*
X866399Y545650D01*
X867099Y545117D01*
X867399Y544317D01*
Y540450D01*
G01X872199Y544050D02*
X875399D01*
X875099Y544983D01*
X874599Y545517D01*
X873899Y545783D01*
X873199Y545650D01*
X872599Y545250D01*
X872199Y544317D01*
X871999Y543516D01*
Y542717D01*
X872199Y541917D01*
X872699Y541117D01*
X873299Y540583D01*
X873999Y540450D01*
X874699Y540717D01*
X875399Y541516D01*
G01X879999Y540450D02*
Y545783D01*
G01Y544450D02*
X880399Y545117D01*
X880999Y545650D01*
X881799Y545783D01*
X882499Y545650D01*
X883099Y545117D01*
X883399Y544183D01*
Y540450D01*
G01X899299Y545117D02*
X898599Y545650D01*
X897999Y545783D01*
X897199Y545517D01*
X896599Y544983D01*
X896199Y544050D01*
X896099Y543117D01*
X896199Y542183D01*
X896599Y541383D01*
X897199Y540717D01*
X897999Y540450D01*
X898699Y540717D01*
X899299Y541250D01*
G01X905699Y540450D02*
X905099Y540583D01*
X904499Y541117D01*
X904099Y542050D01*
X903899Y543117D01*
X904099Y544183D01*
X904499Y545117D01*
X905099Y545650D01*
X905699Y545783D01*
X906299Y545650D01*
X906899Y545117D01*
X907299Y544183D01*
X907399Y543117D01*
X907299Y542050D01*
X906899Y541117D01*
X906299Y540583D01*
X905699Y540450D01*
G01X911999D02*
Y545783D01*
G01Y544450D02*
X912399Y545117D01*
X912999Y545650D01*
X913799Y545783D01*
X914499Y545650D01*
X915099Y545117D01*
X915399Y544183D01*
Y540450D01*
G01X919899Y545783D02*
X921699Y540450D01*
X923499Y545783D01*
G01X928199Y544050D02*
X931399D01*
X931099Y544983D01*
X930599Y545517D01*
X929899Y545783D01*
X929199Y545650D01*
X928599Y545250D01*
X928199Y544317D01*
X927999Y543516D01*
Y542717D01*
X928199Y541917D01*
X928699Y541117D01*
X929299Y540583D01*
X929999Y540450D01*
X930699Y540717D01*
X931399Y541516D01*
G01X936299Y540450D02*
Y545783D01*
G01Y544717D02*
X936799Y545250D01*
X937299Y545650D01*
X937999Y545783D01*
X938499Y545650D01*
X939099Y545250D01*
G01X945699Y548450D02*
Y540450D01*
G01X944299Y545783D02*
X947099D01*
G01X959499Y542050D02*
X960099Y541117D01*
X960899Y540583D01*
X961799Y540450D01*
X962599Y540583D01*
X963399Y541250D01*
X963899Y542050D01*
X963999Y542850D01*
X963799Y543783D01*
X963099Y544450D01*
X962399Y544717D01*
X961499D01*
G01X962399D02*
X962999Y545117D01*
X963499Y545783D01*
X963699Y546583D01*
X963499Y547383D01*
X962999Y548050D01*
X962099Y548450D01*
X961199Y548317D01*
X960299Y547783D01*
G01X969699Y540183D02*
X969499Y540317D01*
Y540583D01*
X969699Y540717D01*
X969899Y540583D01*
Y540317D01*
X969699Y540183D01*
G01X977699Y540450D02*
Y548450D01*
X976499Y546850D01*
G01Y540450D02*
X978899D01*
G01X985699D02*
X986399Y540583D01*
X987199Y540983D01*
X987699Y541650D01*
X987899Y542583D01*
X987699Y543516D01*
X987099Y544317D01*
X986199Y544717D01*
X985199D01*
X984599Y544983D01*
X984099Y545650D01*
X983899Y546583D01*
X984199Y547517D01*
X984899Y548183D01*
X985699Y548450D01*
X986499Y548183D01*
X987199Y547517D01*
X987499Y546583D01*
X987299Y545650D01*
X986799Y544983D01*
X986199Y544717D01*
X985199D01*
X984299Y544317D01*
X983699Y543516D01*
X983499Y542583D01*
X983699Y541650D01*
X984199Y540983D01*
X984999Y540583D01*
X985699Y540450D01*
G01X990699D02*
Y545783D01*
G01Y544317D02*
X990999Y544983D01*
X991499Y545517D01*
X992199Y545783D01*
X992899Y545517D01*
X993399Y544983D01*
X993699Y544317D01*
Y540450D01*
G01Y544317D02*
X993999Y544983D01*
X994499Y545517D01*
X995199Y545783D01*
X995899Y545517D01*
X996399Y544983D01*
X996699Y544183D01*
Y540450D01*
G01X998699D02*
Y545783D01*
G01Y544317D02*
X998999Y544983D01*
X999499Y545517D01*
X1000199Y545783D01*
X1000899Y545517D01*
X1001399Y544983D01*
X1001699Y544317D01*
Y540450D01*
G01Y544317D02*
X1001999Y544983D01*
X1002499Y545517D01*
X1003199Y545783D01*
X1003899Y545517D01*
X1004399Y544983D01*
X1004699Y544183D01*
Y540450D01*
G01X1017699Y545783D02*
Y540450D01*
G01Y547917D02*
X1017499Y548050D01*
Y548317D01*
X1017699Y548450D01*
X1017899Y548317D01*
Y548050D01*
X1017699Y547917D01*
G01X1023999Y540450D02*
Y545783D01*
G01Y544450D02*
X1024399Y545117D01*
X1024999Y545650D01*
X1025799Y545783D01*
X1026499Y545650D01*
X1027099Y545117D01*
X1027399Y544183D01*
Y540450D01*
G01X1033699Y548450D02*
Y540450D01*
G01X1032299Y545783D02*
X1035099D01*
G01X1041699Y540450D02*
X1041099Y540583D01*
X1040499Y541117D01*
X1040099Y542050D01*
X1039899Y543117D01*
X1040099Y544183D01*
X1040499Y545117D01*
X1041099Y545650D01*
X1041699Y545783D01*
X1042299Y545650D01*
X1042899Y545117D01*
X1043299Y544183D01*
X1043399Y543117D01*
X1043299Y542050D01*
X1042899Y541117D01*
X1042299Y540583D01*
X1041699Y540450D01*
G01X1057699D02*
Y548450D01*
X1056499Y546850D01*
G01Y540450D02*
X1058899D01*
G01X1063799Y547117D02*
X1064399Y547917D01*
X1065099Y548317D01*
X1065899Y548450D01*
X1066899Y548183D01*
X1067599Y547517D01*
X1067799Y546717D01*
X1067699Y545916D01*
X1067299Y545250D01*
X1065299Y543917D01*
X1064399Y542983D01*
X1063799Y541650D01*
X1063599Y540450D01*
X1067799D01*
G01X1071499Y541650D02*
X1072099Y540983D01*
X1072799Y540583D01*
X1073699Y540450D01*
X1074599Y540717D01*
X1075299Y541250D01*
X1075799Y542183D01*
X1075899Y543250D01*
X1075699Y544317D01*
X1075199Y544983D01*
X1074499Y545517D01*
X1073799Y545650D01*
X1073099Y545517D01*
X1072199Y544983D01*
X1072499Y548450D01*
X1075199D01*
G01X1081699Y540183D02*
X1081499Y540317D01*
Y540583D01*
X1081699Y540717D01*
X1081899Y540583D01*
Y540317D01*
X1081699Y540183D01*
G01X1089699Y540450D02*
Y548450D01*
X1088499Y546850D01*
G01Y540450D02*
X1090899D01*
G01X1095999Y541383D02*
X1096699Y540717D01*
X1097499Y540450D01*
X1098299Y540717D01*
X1098999Y541516D01*
X1099499Y542717D01*
X1099699Y543917D01*
Y545383D01*
X1099499Y546583D01*
X1098999Y547650D01*
X1098399Y548183D01*
X1097699Y548450D01*
X1096899Y548183D01*
X1096299Y547650D01*
X1095899Y546850D01*
X1095699Y545783D01*
X1095899Y544850D01*
X1096399Y543917D01*
X1096999Y543383D01*
X1097699Y543250D01*
X1098499Y543516D01*
X1099099Y544183D01*
X1099699Y545383D01*
G01X1103799Y543783D02*
X1104499Y544717D01*
X1105099Y545250D01*
X1105899Y545517D01*
X1106599Y545250D01*
X1107099Y544717D01*
X1107499Y543917D01*
X1107599Y542983D01*
X1107499Y542183D01*
X1107099Y541383D01*
X1106499Y540717D01*
X1105799Y540450D01*
X1104999Y540717D01*
X1104299Y541516D01*
X1103899Y542717D01*
X1103799Y544050D01*
X1103999Y545783D01*
X1104299Y546717D01*
X1104799Y547650D01*
X1105499Y548317D01*
X1106199Y548450D01*
X1106899Y548183D01*
X1107399Y547517D01*
G01X1113699Y540450D02*
X1114399Y540583D01*
X1115199Y540983D01*
X1115699Y541650D01*
X1115899Y542583D01*
X1115699Y543516D01*
X1115099Y544317D01*
X1114199Y544717D01*
X1113199D01*
X1112599Y544983D01*
X1112099Y545650D01*
X1111899Y546583D01*
X1112199Y547517D01*
X1112899Y548183D01*
X1113699Y548450D01*
X1114499Y548183D01*
X1115199Y547517D01*
X1115499Y546583D01*
X1115299Y545650D01*
X1114799Y544983D01*
X1114199Y544717D01*
X1113199D01*
X1112299Y544317D01*
X1111699Y543516D01*
X1111499Y542583D01*
X1111699Y541650D01*
X1112199Y540983D01*
X1112999Y540583D01*
X1113699Y540450D01*
G01X1118699D02*
Y545783D01*
G01Y544317D02*
X1118999Y544983D01*
X1119499Y545517D01*
X1120199Y545783D01*
X1120899Y545517D01*
X1121399Y544983D01*
X1121699Y544317D01*
Y540450D01*
G01Y544317D02*
X1121999Y544983D01*
X1122499Y545517D01*
X1123199Y545783D01*
X1123899Y545517D01*
X1124399Y544983D01*
X1124699Y544183D01*
Y540450D01*
G01X1129699Y545783D02*
Y540450D01*
G01Y547917D02*
X1129499Y548050D01*
Y548317D01*
X1129699Y548450D01*
X1129899Y548317D01*
Y548050D01*
X1129699Y547917D01*
G01X1137699Y540450D02*
Y548450D01*
G01X1145499Y538983D02*
X1145899Y540717D01*
G01X1161699Y548450D02*
Y540450D01*
G01X1160299Y545783D02*
X1163099D01*
G01X1167999Y540450D02*
Y548450D01*
G01Y544583D02*
X1168499Y545250D01*
X1168999Y545650D01*
X1169799Y545783D01*
X1170399Y545650D01*
X1171099Y545117D01*
X1171399Y544317D01*
Y540450D01*
G01X1176199Y544050D02*
X1179399D01*
X1179099Y544983D01*
X1178599Y545517D01*
X1177899Y545783D01*
X1177199Y545650D01*
X1176599Y545250D01*
X1176199Y544317D01*
X1175999Y543516D01*
Y542717D01*
X1176199Y541917D01*
X1176699Y541117D01*
X1177299Y540583D01*
X1177999Y540450D01*
X1178699Y540717D01*
X1179399Y541516D01*
G01X1195499Y548450D02*
Y540450D01*
G01Y541650D02*
X1195099Y540983D01*
X1194499Y540583D01*
X1193799Y540450D01*
X1192999Y540717D01*
X1192399Y541383D01*
X1191999Y542183D01*
X1191899Y543117D01*
X1191999Y544050D01*
X1192399Y544850D01*
X1192999Y545517D01*
X1193799Y545783D01*
X1194499Y545650D01*
X1194999Y545383D01*
X1195499Y544850D01*
G01X1201699Y545783D02*
Y540450D01*
G01Y547917D02*
X1201499Y548050D01*
Y548317D01*
X1201699Y548450D01*
X1201899Y548317D01*
Y548050D01*
X1201699Y547917D01*
G01X1209099Y540450D02*
Y547250D01*
X1209299Y547917D01*
X1209699Y548317D01*
X1210299Y548450D01*
X1210899Y548183D01*
X1211199Y547517D01*
G01X1209999Y545250D02*
X1207999D01*
G01X1217099Y540450D02*
Y547250D01*
X1217299Y547917D01*
X1217699Y548317D01*
X1218299Y548450D01*
X1218899Y548183D01*
X1219199Y547517D01*
G01X1217999Y545250D02*
X1215999D01*
G01X1224199Y544050D02*
X1227399D01*
X1227099Y544983D01*
X1226599Y545517D01*
X1225899Y545783D01*
X1225199Y545650D01*
X1224599Y545250D01*
X1224199Y544317D01*
X1223999Y543516D01*
Y542717D01*
X1224199Y541917D01*
X1224699Y541117D01*
X1225299Y540583D01*
X1225999Y540450D01*
X1226699Y540717D01*
X1227399Y541516D01*
G01X1232299Y540450D02*
Y545783D01*
G01Y544717D02*
X1232799Y545250D01*
X1233299Y545650D01*
X1233999Y545783D01*
X1234499Y545650D01*
X1235099Y545250D01*
G01X1240199Y544050D02*
X1243399D01*
X1243099Y544983D01*
X1242599Y545517D01*
X1241899Y545783D01*
X1241199Y545650D01*
X1240599Y545250D01*
X1240199Y544317D01*
X1239999Y543516D01*
Y542717D01*
X1240199Y541917D01*
X1240699Y541117D01*
X1241299Y540583D01*
X1241999Y540450D01*
X1242699Y540717D01*
X1243399Y541516D01*
G01X1247999Y540450D02*
Y545783D01*
G01Y544450D02*
X1248399Y545117D01*
X1248999Y545650D01*
X1249799Y545783D01*
X1250499Y545650D01*
X1251099Y545117D01*
X1251399Y544183D01*
Y540450D01*
G01X1259299Y545117D02*
X1258599Y545650D01*
X1257999Y545783D01*
X1257199Y545517D01*
X1256599Y544983D01*
X1256199Y544050D01*
X1256099Y543117D01*
X1256199Y542183D01*
X1256599Y541383D01*
X1257199Y540717D01*
X1257999Y540450D01*
X1258699Y540717D01*
X1259299Y541250D01*
G01X1264199Y544050D02*
X1267399D01*
X1267099Y544983D01*
X1266599Y545517D01*
X1265899Y545783D01*
X1265199Y545650D01*
X1264599Y545250D01*
X1264199Y544317D01*
X1263999Y543516D01*
Y542717D01*
X1264199Y541917D01*
X1264699Y541117D01*
X1265299Y540583D01*
X1265999Y540450D01*
X1266699Y540717D01*
X1267399Y541516D01*
G01X1279899Y540450D02*
Y548450D01*
G01Y544450D02*
X1280399Y545250D01*
X1280999Y545650D01*
X1281599Y545783D01*
X1282499Y545517D01*
X1283099Y544983D01*
X1283499Y544050D01*
Y542983D01*
X1283299Y541917D01*
X1282899Y541117D01*
X1282199Y540583D01*
X1281599Y540450D01*
X1280999Y540583D01*
X1280399Y540983D01*
X1279899Y541650D01*
G01X1288199Y544050D02*
X1291399D01*
X1291099Y544983D01*
X1290599Y545517D01*
X1289899Y545783D01*
X1289199Y545650D01*
X1288599Y545250D01*
X1288199Y544317D01*
X1287999Y543516D01*
Y542717D01*
X1288199Y541917D01*
X1288699Y541117D01*
X1289299Y540583D01*
X1289999Y540450D01*
X1290699Y540717D01*
X1291399Y541516D01*
G01X1297699Y548450D02*
Y540450D01*
G01X1296299Y545783D02*
X1299099D01*
G01X1303199D02*
X1304399Y540450D01*
X1305699Y545783D01*
X1306999Y540450D01*
X1308199Y545783D01*
G01X1312199Y544050D02*
X1315399D01*
X1315099Y544983D01*
X1314599Y545517D01*
X1313899Y545783D01*
X1313199Y545650D01*
X1312599Y545250D01*
X1312199Y544317D01*
X1311999Y543516D01*
Y542717D01*
X1312199Y541917D01*
X1312699Y541117D01*
X1313299Y540583D01*
X1313999Y540450D01*
X1314699Y540717D01*
X1315399Y541516D01*
G01X1320199Y544050D02*
X1323399D01*
X1323099Y544983D01*
X1322599Y545517D01*
X1321899Y545783D01*
X1321199Y545650D01*
X1320599Y545250D01*
X1320199Y544317D01*
X1319999Y543516D01*
Y542717D01*
X1320199Y541917D01*
X1320699Y541117D01*
X1321299Y540583D01*
X1321999Y540450D01*
X1322699Y540717D01*
X1323399Y541516D01*
G01X1327999Y540450D02*
Y545783D01*
G01Y544450D02*
X1328399Y545117D01*
X1328999Y545650D01*
X1329799Y545783D01*
X1330499Y545650D01*
X1331099Y545117D01*
X1331399Y544183D01*
Y540450D01*
G01X1345699D02*
Y548450D01*
X1344499Y546850D01*
G01Y540450D02*
X1346899D01*
G01X1351799Y547117D02*
X1352399Y547917D01*
X1353099Y548317D01*
X1353899Y548450D01*
X1354899Y548183D01*
X1355599Y547517D01*
X1355799Y546717D01*
X1355699Y545916D01*
X1355299Y545250D01*
X1353299Y543917D01*
X1352399Y542983D01*
X1351799Y541650D01*
X1351599Y540450D01*
X1355799D01*
G01X1359799Y543783D02*
X1360499Y544717D01*
X1361099Y545250D01*
X1361899Y545517D01*
X1362599Y545250D01*
X1363099Y544717D01*
X1363499Y543917D01*
X1363599Y542983D01*
X1363499Y542183D01*
X1363099Y541383D01*
X1362499Y540717D01*
X1361799Y540450D01*
X1360999Y540717D01*
X1360299Y541516D01*
X1359899Y542717D01*
X1359799Y544050D01*
X1359999Y545783D01*
X1360299Y546717D01*
X1360799Y547650D01*
X1361499Y548317D01*
X1362199Y548450D01*
X1362899Y548183D01*
X1363399Y547517D01*
G01X1366699Y540450D02*
Y545783D01*
G01Y544317D02*
X1366999Y544983D01*
X1367499Y545517D01*
X1368199Y545783D01*
X1368899Y545517D01*
X1369399Y544983D01*
X1369699Y544317D01*
Y540450D01*
G01Y544317D02*
X1369999Y544983D01*
X1370499Y545517D01*
X1371199Y545783D01*
X1371899Y545517D01*
X1372399Y544983D01*
X1372699Y544183D01*
Y540450D01*
G01X1377699Y545783D02*
Y540450D01*
G01Y547917D02*
X1377499Y548050D01*
Y548317D01*
X1377699Y548450D01*
X1377899Y548317D01*
Y548050D01*
X1377699Y547917D01*
G01X1385699Y540450D02*
Y548450D01*
G01X1403499Y540450D02*
Y545783D01*
G01Y544850D02*
X1403099Y545383D01*
X1402499Y545650D01*
X1401799Y545783D01*
X1401099Y545517D01*
X1400499Y544983D01*
X1400099Y544183D01*
X1399899Y543117D01*
X1400099Y542050D01*
X1400499Y541250D01*
X1401099Y540717D01*
X1401799Y540450D01*
X1402499Y540583D01*
X1403099Y540983D01*
X1403499Y541516D01*
G01X1407999Y540450D02*
Y545783D01*
G01Y544450D02*
X1408399Y545117D01*
X1408999Y545650D01*
X1409799Y545783D01*
X1410499Y545650D01*
X1411099Y545117D01*
X1411399Y544183D01*
Y540450D01*
G01X1419499Y548450D02*
Y540450D01*
G01Y541650D02*
X1419099Y540983D01*
X1418499Y540583D01*
X1417799Y540450D01*
X1416999Y540717D01*
X1416399Y541383D01*
X1415999Y542183D01*
X1415899Y543117D01*
X1415999Y544050D01*
X1416399Y544850D01*
X1416999Y545517D01*
X1417799Y545783D01*
X1418499Y545650D01*
X1418999Y545383D01*
X1419499Y544850D01*
G01X1433699Y540450D02*
Y548450D01*
X1432499Y546850D01*
G01Y540450D02*
X1434899D01*
G01X1439799Y547117D02*
X1440399Y547917D01*
X1441099Y548317D01*
X1441899Y548450D01*
X1442899Y548183D01*
X1443599Y547517D01*
X1443799Y546717D01*
X1443699Y545916D01*
X1443299Y545250D01*
X1441299Y543917D01*
X1440399Y542983D01*
X1439799Y541650D01*
X1439599Y540450D01*
X1443799D01*
G01X1447499Y541650D02*
X1448099Y540983D01*
X1448799Y540583D01*
X1449699Y540450D01*
X1450599Y540717D01*
X1451299Y541250D01*
X1451799Y542183D01*
X1451899Y543250D01*
X1451699Y544317D01*
X1451199Y544983D01*
X1450499Y545517D01*
X1449799Y545650D01*
X1449099Y545517D01*
X1448199Y544983D01*
X1448499Y548450D01*
X1451199D01*
G01X1457699Y540183D02*
X1457499Y540317D01*
Y540583D01*
X1457699Y540717D01*
X1457899Y540583D01*
Y540317D01*
X1457699Y540183D01*
G01X1465699Y540450D02*
Y548450D01*
X1464499Y546850D01*
G01Y540450D02*
X1466899D01*
G01X1471999Y541383D02*
X1472699Y540717D01*
X1473499Y540450D01*
X1474299Y540717D01*
X1474999Y541516D01*
X1475499Y542717D01*
X1475699Y543917D01*
Y545383D01*
X1475499Y546583D01*
X1474999Y547650D01*
X1474399Y548183D01*
X1473699Y548450D01*
X1472899Y548183D01*
X1472299Y547650D01*
X1471899Y546850D01*
X1471699Y545783D01*
X1471899Y544850D01*
X1472399Y543917D01*
X1472999Y543383D01*
X1473699Y543250D01*
X1474499Y543516D01*
X1475099Y544183D01*
X1475699Y545383D01*
G01X1479799Y543783D02*
X1480499Y544717D01*
X1481099Y545250D01*
X1481899Y545517D01*
X1482599Y545250D01*
X1483099Y544717D01*
X1483499Y543917D01*
X1483599Y542983D01*
X1483499Y542183D01*
X1483099Y541383D01*
X1482499Y540717D01*
X1481799Y540450D01*
X1480999Y540717D01*
X1480299Y541516D01*
X1479899Y542717D01*
X1479799Y544050D01*
X1479999Y545783D01*
X1480299Y546717D01*
X1480799Y547650D01*
X1481499Y548317D01*
X1482199Y548450D01*
X1482899Y548183D01*
X1483399Y547517D01*
G01X1489699Y540450D02*
X1490399Y540583D01*
X1491199Y540983D01*
X1491699Y541650D01*
X1491899Y542583D01*
X1491699Y543516D01*
X1491099Y544317D01*
X1490199Y544717D01*
X1489199D01*
X1488599Y544983D01*
X1488099Y545650D01*
X1487899Y546583D01*
X1488199Y547517D01*
X1488899Y548183D01*
X1489699Y548450D01*
X1490499Y548183D01*
X1491199Y547517D01*
X1491499Y546583D01*
X1491299Y545650D01*
X1490799Y544983D01*
X1490199Y544717D01*
X1489199D01*
X1488299Y544317D01*
X1487699Y543516D01*
X1487499Y542583D01*
X1487699Y541650D01*
X1488199Y540983D01*
X1488999Y540583D01*
X1489699Y540450D01*
G01X1505699Y545783D02*
Y540450D01*
G01Y547917D02*
X1505499Y548050D01*
Y548317D01*
X1505699Y548450D01*
X1505899Y548317D01*
Y548050D01*
X1505699Y547917D01*
G01X1512199Y541383D02*
X1512699Y540850D01*
X1513399Y540450D01*
X1513999D01*
X1514599Y540717D01*
X1514999Y541117D01*
X1515199Y541650D01*
X1515099Y542450D01*
X1514699Y542850D01*
X1512899Y543650D01*
X1512499Y544583D01*
X1512699Y545250D01*
X1513099Y545650D01*
X1513699Y545783D01*
X1514299Y545650D01*
X1514899Y545250D01*
G01X1529699Y540450D02*
Y548450D01*
G01X1536199Y544050D02*
X1539399D01*
X1539099Y544983D01*
X1538599Y545517D01*
X1537899Y545783D01*
X1537199Y545650D01*
X1536599Y545250D01*
X1536199Y544317D01*
X1535999Y543516D01*
Y542717D01*
X1536199Y541917D01*
X1536699Y541117D01*
X1537299Y540583D01*
X1537999Y540450D01*
X1538699Y540717D01*
X1539399Y541516D01*
G01X1544199Y541383D02*
X1544699Y540850D01*
X1545399Y540450D01*
X1545999D01*
X1546599Y540717D01*
X1546999Y541117D01*
X1547199Y541650D01*
X1547099Y542450D01*
X1546699Y542850D01*
X1544899Y543650D01*
X1544499Y544583D01*
X1544699Y545250D01*
X1545099Y545650D01*
X1545699Y545783D01*
X1546299Y545650D01*
X1546899Y545250D01*
G01X1552199Y541383D02*
X1552699Y540850D01*
X1553399Y540450D01*
X1553999D01*
X1554599Y540717D01*
X1554999Y541117D01*
X1555199Y541650D01*
X1555099Y542450D01*
X1554699Y542850D01*
X1552899Y543650D01*
X1552499Y544583D01*
X1552699Y545250D01*
X1553099Y545650D01*
X1553699Y545783D01*
X1554299Y545650D01*
X1554899Y545250D01*
G01X1569699Y548450D02*
Y540450D01*
G01X1568299Y545783D02*
X1571099D01*
G01X1575999Y540450D02*
Y548450D01*
G01Y544583D02*
X1576499Y545250D01*
X1576999Y545650D01*
X1577799Y545783D01*
X1578399Y545650D01*
X1579099Y545117D01*
X1579399Y544317D01*
Y540450D01*
G01X1587499D02*
Y545783D01*
G01Y544850D02*
X1587099Y545383D01*
X1586499Y545650D01*
X1585799Y545783D01*
X1585099Y545517D01*
X1584499Y544983D01*
X1584099Y544183D01*
X1583899Y543117D01*
X1584099Y542050D01*
X1584499Y541250D01*
X1585099Y540717D01*
X1585799Y540450D01*
X1586499Y540583D01*
X1587099Y540983D01*
X1587499Y541516D01*
G01X1591999Y540450D02*
Y545783D01*
G01Y544450D02*
X1592399Y545117D01*
X1592999Y545650D01*
X1593799Y545783D01*
X1594499Y545650D01*
X1595099Y545117D01*
X1595399Y544183D01*
Y540450D01*
G01X1609699D02*
Y548450D01*
X1608499Y546850D01*
G01Y540450D02*
X1610899D01*
G01X1622699D02*
Y545783D01*
G01Y544317D02*
X1622999Y544983D01*
X1623499Y545517D01*
X1624199Y545783D01*
X1624899Y545517D01*
X1625399Y544983D01*
X1625699Y544317D01*
Y540450D01*
G01Y544317D02*
X1625999Y544983D01*
X1626499Y545517D01*
X1627199Y545783D01*
X1627899Y545517D01*
X1628399Y544983D01*
X1628699Y544183D01*
Y540450D01*
G01X1633699Y545783D02*
Y540450D01*
G01Y547917D02*
X1633499Y548050D01*
Y548317D01*
X1633699Y548450D01*
X1633899Y548317D01*
Y548050D01*
X1633699Y547917D01*
G01X1641699Y540450D02*
Y548450D01*
G01X1649499Y538983D02*
X1649899Y540717D01*
G01X862199Y777850D02*
X864699Y785850D01*
X867199Y777850D01*
G01X866299Y780650D02*
X863099D01*
G01X872699Y777850D02*
Y785850D01*
G01X880699Y783183D02*
Y777850D01*
G01Y785317D02*
X880499Y785450D01*
Y785717D01*
X880699Y785850D01*
X880899Y785717D01*
Y785450D01*
X880699Y785317D01*
G01X887299Y775850D02*
X887999Y775317D01*
X888799Y775183D01*
X889499Y775317D01*
X890099Y775983D01*
X890499Y776917D01*
Y783183D01*
G01Y782117D02*
X890099Y782650D01*
X889499Y783050D01*
X888799Y783183D01*
X887999Y782917D01*
X887499Y782383D01*
X887099Y781450D01*
X886899Y780517D01*
X886999Y779717D01*
X887399Y778783D01*
X887999Y778117D01*
X888799Y777850D01*
X889399Y777983D01*
X890099Y778517D01*
X890499Y779050D01*
G01X894999Y777850D02*
Y783183D01*
G01Y781850D02*
X895399Y782517D01*
X895999Y783050D01*
X896799Y783183D01*
X897499Y783050D01*
X898099Y782517D01*
X898399Y781583D01*
Y777850D01*
G01X901699D02*
Y783183D01*
G01Y781717D02*
X901999Y782383D01*
X902499Y782917D01*
X903199Y783183D01*
X903899Y782917D01*
X904399Y782383D01*
X904699Y781717D01*
Y777850D01*
G01Y781717D02*
X904999Y782383D01*
X905499Y782917D01*
X906199Y783183D01*
X906899Y782917D01*
X907399Y782383D01*
X907699Y781583D01*
Y777850D01*
G01X911199Y781450D02*
X914399D01*
X914099Y782383D01*
X913599Y782917D01*
X912899Y783183D01*
X912199Y783050D01*
X911599Y782650D01*
X911199Y781717D01*
X910999Y780916D01*
Y780117D01*
X911199Y779317D01*
X911699Y778517D01*
X912299Y777983D01*
X912999Y777850D01*
X913699Y778117D01*
X914399Y778916D01*
G01X918999Y777850D02*
Y783183D01*
G01Y781850D02*
X919399Y782517D01*
X919999Y783050D01*
X920799Y783183D01*
X921499Y783050D01*
X922099Y782517D01*
X922399Y781583D01*
Y777850D01*
G01X928699Y785850D02*
Y777850D01*
G01X927299Y783183D02*
X930099D01*
G01X882599Y721916D02*
X883399Y721250D01*
X884299Y720850D01*
X885099D01*
X885899Y721250D01*
X886499Y721916D01*
X886799Y722850D01*
X886599Y723783D01*
X886099Y724583D01*
X885199Y725117D01*
X883999Y725383D01*
X883299Y725917D01*
X882999Y726850D01*
X883199Y727783D01*
X883699Y728450D01*
X884399Y728850D01*
X885099D01*
X885799Y728583D01*
X886399Y727917D01*
G01X892699Y726183D02*
Y720850D01*
G01Y728317D02*
X892499Y728450D01*
Y728717D01*
X892699Y728850D01*
X892899Y728717D01*
Y728450D01*
X892699Y728317D01*
G01X899199Y726183D02*
X902199D01*
X899199Y720850D01*
X902199D01*
G01X907199Y724450D02*
X910399D01*
X910099Y725383D01*
X909599Y725917D01*
X908899Y726183D01*
X908199Y726050D01*
X907599Y725650D01*
X907199Y724717D01*
X906999Y723916D01*
Y723117D01*
X907199Y722317D01*
X907699Y721517D01*
X908299Y720983D01*
X908999Y720850D01*
X909699Y721117D01*
X910399Y721916D01*
G01X945099Y629350D02*
Y637350D01*
G01X949299D02*
Y629350D01*
G01Y633350D02*
X945099D01*
G01X955199Y629350D02*
X954599Y629483D01*
X953999Y630017D01*
X953599Y630950D01*
X953399Y632017D01*
X953599Y633083D01*
X953999Y634017D01*
X954599Y634550D01*
X955199Y634683D01*
X955799Y634550D01*
X956399Y634017D01*
X956799Y633083D01*
X956899Y632017D01*
X956799Y630950D01*
X956399Y630017D01*
X955799Y629483D01*
X955199Y629350D01*
G01X963199D02*
Y637350D01*
G01X969699Y632950D02*
X972899D01*
X972599Y633883D01*
X972099Y634417D01*
X971399Y634683D01*
X970699Y634550D01*
X970099Y634150D01*
X969699Y633217D01*
X969499Y632416D01*
Y631617D01*
X969699Y630817D01*
X970199Y630017D01*
X970799Y629483D01*
X971499Y629350D01*
X972199Y629617D01*
X972899Y630416D01*
G01X984199Y637350D02*
X985599Y629350D01*
X987199Y637350D01*
X988799Y629350D01*
X990199Y637350D01*
G01X996999Y629350D02*
Y634683D01*
G01Y633750D02*
X996599Y634283D01*
X995999Y634550D01*
X995299Y634683D01*
X994599Y634417D01*
X993999Y633883D01*
X993599Y633083D01*
X993399Y632017D01*
X993599Y630950D01*
X993999Y630150D01*
X994599Y629617D01*
X995299Y629350D01*
X995999Y629483D01*
X996599Y629883D01*
X996999Y630416D01*
G01X1003199Y629350D02*
Y637350D01*
G01X1011199Y629350D02*
Y637350D01*
G01X1025199Y629350D02*
Y637350D01*
X1027699D01*
X1028499Y636950D01*
X1028999Y636417D01*
X1029199Y635350D01*
X1028999Y634283D01*
X1028399Y633617D01*
X1027699Y633217D01*
X1025199D01*
G01X1027699D02*
X1029199Y629350D01*
G01X1035199D02*
X1034599Y629483D01*
X1033999Y630017D01*
X1033599Y630950D01*
X1033399Y632017D01*
X1033599Y633083D01*
X1033999Y634017D01*
X1034599Y634550D01*
X1035199Y634683D01*
X1035799Y634550D01*
X1036399Y634017D01*
X1036799Y633083D01*
X1036899Y632017D01*
X1036799Y630950D01*
X1036399Y630017D01*
X1035799Y629483D01*
X1035199Y629350D01*
G01X1041499Y634683D02*
Y630950D01*
X1041899Y630017D01*
X1042499Y629483D01*
X1043199Y629350D01*
X1043899Y629483D01*
X1044499Y630017D01*
X1044899Y630950D01*
G01Y629350D02*
Y634683D01*
G01X1049799Y627350D02*
X1050499Y626817D01*
X1051299Y626683D01*
X1051999Y626817D01*
X1052599Y627483D01*
X1052999Y628417D01*
Y634683D01*
G01Y633617D02*
X1052599Y634150D01*
X1051999Y634550D01*
X1051299Y634683D01*
X1050499Y634417D01*
X1049999Y633883D01*
X1049599Y632950D01*
X1049399Y632017D01*
X1049499Y631217D01*
X1049899Y630283D01*
X1050499Y629617D01*
X1051299Y629350D01*
X1051899Y629483D01*
X1052599Y630017D01*
X1052999Y630550D01*
G01X1057499Y629350D02*
Y637350D01*
G01Y633483D02*
X1057999Y634150D01*
X1058499Y634550D01*
X1059299Y634683D01*
X1059899Y634550D01*
X1060599Y634017D01*
X1060899Y633217D01*
Y629350D01*
G01X1065499D02*
Y634683D01*
G01Y633350D02*
X1065899Y634017D01*
X1066499Y634550D01*
X1067299Y634683D01*
X1067999Y634550D01*
X1068599Y634017D01*
X1068899Y633083D01*
Y629350D01*
G01X1073699Y632950D02*
X1076899D01*
X1076599Y633883D01*
X1076099Y634417D01*
X1075399Y634683D01*
X1074699Y634550D01*
X1074099Y634150D01*
X1073699Y633217D01*
X1073499Y632416D01*
Y631617D01*
X1073699Y630817D01*
X1074199Y630017D01*
X1074799Y629483D01*
X1075499Y629350D01*
X1076199Y629617D01*
X1076899Y630416D01*
G01X1081699Y630283D02*
X1082199Y629750D01*
X1082899Y629350D01*
X1083499D01*
X1084099Y629617D01*
X1084499Y630017D01*
X1084699Y630550D01*
X1084599Y631350D01*
X1084199Y631750D01*
X1082399Y632550D01*
X1081999Y633483D01*
X1082199Y634150D01*
X1082599Y634550D01*
X1083199Y634683D01*
X1083799Y634550D01*
X1084399Y634150D01*
G01X1089699Y630283D02*
X1090199Y629750D01*
X1090899Y629350D01*
X1091499D01*
X1092099Y629617D01*
X1092499Y630017D01*
X1092699Y630550D01*
X1092599Y631350D01*
X1092199Y631750D01*
X1090399Y632550D01*
X1089999Y633483D01*
X1090199Y634150D01*
X1090599Y634550D01*
X1091199Y634683D01*
X1091799Y634550D01*
X1092399Y634150D01*
G01X946199Y641350D02*
X945399Y641483D01*
X944699Y642017D01*
X944099Y642817D01*
X943699Y643750D01*
X943499Y644817D01*
Y645883D01*
X943699Y646950D01*
X944099Y647883D01*
X944699Y648683D01*
X945399Y649217D01*
X946199Y649350D01*
X946999Y649217D01*
X947699Y648683D01*
X948299Y647883D01*
X948699Y646950D01*
X948899Y645883D01*
Y644817D01*
X948699Y643750D01*
X948299Y642817D01*
X947699Y642017D01*
X946999Y641483D01*
X946199Y641350D01*
G01X954199Y649350D02*
Y641350D01*
G01X952799Y646683D02*
X955599D01*
G01X960499Y641350D02*
Y649350D01*
G01Y645483D02*
X960999Y646150D01*
X961499Y646550D01*
X962299Y646683D01*
X962899Y646550D01*
X963599Y646017D01*
X963899Y645217D01*
Y641350D01*
G01X968699Y644950D02*
X971899D01*
X971599Y645883D01*
X971099Y646417D01*
X970399Y646683D01*
X969699Y646550D01*
X969099Y646150D01*
X968699Y645217D01*
X968499Y644416D01*
Y643617D01*
X968699Y642817D01*
X969199Y642017D01*
X969799Y641483D01*
X970499Y641350D01*
X971199Y641617D01*
X971899Y642416D01*
G01X976799Y641350D02*
Y646683D01*
G01Y645617D02*
X977299Y646150D01*
X977799Y646550D01*
X978499Y646683D01*
X978999Y646550D01*
X979599Y646150D01*
G01X984699Y642283D02*
X985199Y641750D01*
X985899Y641350D01*
X986499D01*
X987099Y641617D01*
X987499Y642017D01*
X987699Y642550D01*
X987599Y643350D01*
X987199Y643750D01*
X985399Y644550D01*
X984999Y645483D01*
X985199Y646150D01*
X985599Y646550D01*
X986199Y646683D01*
X986799Y646550D01*
X987399Y646150D01*
G01X1001699Y638683D02*
X1000699Y640017D01*
X1000199Y641350D01*
Y646683D01*
X1000699Y648017D01*
X1001699Y649350D01*
G01X1010199Y641350D02*
Y649350D01*
G01X1018199Y646683D02*
Y641350D01*
G01Y648817D02*
X1017999Y648950D01*
Y649217D01*
X1018199Y649350D01*
X1018399Y649217D01*
Y648950D01*
X1018199Y648817D01*
G01X1024499Y641350D02*
Y649350D01*
G01X1027699Y646683D02*
X1024499Y643617D01*
G01X1025799Y644817D02*
X1027899Y641350D01*
G01X1032699Y644950D02*
X1035899D01*
X1035599Y645883D01*
X1035099Y646417D01*
X1034399Y646683D01*
X1033699Y646550D01*
X1033099Y646150D01*
X1032699Y645217D01*
X1032499Y644416D01*
Y643617D01*
X1032699Y642817D01*
X1033199Y642017D01*
X1033799Y641483D01*
X1034499Y641350D01*
X1035199Y641617D01*
X1035899Y642416D01*
G01X1048699Y644950D02*
X1051899D01*
X1051599Y645883D01*
X1051099Y646417D01*
X1050399Y646683D01*
X1049699Y646550D01*
X1049099Y646150D01*
X1048699Y645217D01*
X1048499Y644416D01*
Y643617D01*
X1048699Y642817D01*
X1049199Y642017D01*
X1049799Y641483D01*
X1050499Y641350D01*
X1051199Y641617D01*
X1051899Y642416D01*
G01X1058199Y641350D02*
Y649350D01*
G01X1066199Y641350D02*
Y649350D01*
G01X1074199Y646683D02*
Y641350D01*
G01Y648817D02*
X1073999Y648950D01*
Y649217D01*
X1074199Y649350D01*
X1074399Y649217D01*
Y648950D01*
X1074199Y648817D01*
G01X1080399Y638683D02*
Y646683D01*
G01Y645483D02*
X1080899Y646150D01*
X1081399Y646550D01*
X1082199Y646683D01*
X1082899Y646550D01*
X1083599Y645883D01*
X1083899Y644950D01*
X1083999Y644017D01*
X1083899Y643083D01*
X1083599Y642150D01*
X1082999Y641617D01*
X1082199Y641350D01*
X1081499Y641483D01*
X1080799Y641883D01*
X1080399Y642416D01*
G01X1088699Y642283D02*
X1089199Y641750D01*
X1089899Y641350D01*
X1090499D01*
X1091099Y641617D01*
X1091499Y642017D01*
X1091699Y642550D01*
X1091599Y643350D01*
X1091199Y643750D01*
X1089399Y644550D01*
X1088999Y645483D01*
X1089199Y646150D01*
X1089599Y646550D01*
X1090199Y646683D01*
X1090799Y646550D01*
X1091399Y646150D01*
G01X1096699Y644950D02*
X1099899D01*
X1099599Y645883D01*
X1099099Y646417D01*
X1098399Y646683D01*
X1097699Y646550D01*
X1097099Y646150D01*
X1096699Y645217D01*
X1096499Y644416D01*
Y643617D01*
X1096699Y642817D01*
X1097199Y642017D01*
X1097799Y641483D01*
X1098499Y641350D01*
X1099199Y641617D01*
X1099899Y642416D01*
G01X1115999Y641350D02*
Y646683D01*
G01Y645750D02*
X1115599Y646283D01*
X1114999Y646550D01*
X1114299Y646683D01*
X1113599Y646417D01*
X1112999Y645883D01*
X1112599Y645083D01*
X1112399Y644017D01*
X1112599Y642950D01*
X1112999Y642150D01*
X1113599Y641617D01*
X1114299Y641350D01*
X1114999Y641483D01*
X1115599Y641883D01*
X1115999Y642416D01*
G01X1120499Y641350D02*
Y646683D01*
G01Y645350D02*
X1120899Y646017D01*
X1121499Y646550D01*
X1122299Y646683D01*
X1122999Y646550D01*
X1123599Y646017D01*
X1123899Y645083D01*
Y641350D01*
G01X1131999Y649350D02*
Y641350D01*
G01Y642550D02*
X1131599Y641883D01*
X1130999Y641483D01*
X1130299Y641350D01*
X1129499Y641617D01*
X1128899Y642283D01*
X1128499Y643083D01*
X1128399Y644017D01*
X1128499Y644950D01*
X1128899Y645750D01*
X1129499Y646417D01*
X1130299Y646683D01*
X1130999Y646550D01*
X1131499Y646283D01*
X1131999Y645750D01*
G01X1146199Y641350D02*
X1145599Y641483D01*
X1144999Y642017D01*
X1144599Y642950D01*
X1144399Y644017D01*
X1144599Y645083D01*
X1144999Y646017D01*
X1145599Y646550D01*
X1146199Y646683D01*
X1146799Y646550D01*
X1147399Y646017D01*
X1147799Y645083D01*
X1147899Y644017D01*
X1147799Y642950D01*
X1147399Y642017D01*
X1146799Y641483D01*
X1146199Y641350D01*
G01X1154199Y649350D02*
Y641350D01*
G01X1152799Y646683D02*
X1155599D01*
G01X1160499Y641350D02*
Y649350D01*
G01Y645483D02*
X1160999Y646150D01*
X1161499Y646550D01*
X1162299Y646683D01*
X1162899Y646550D01*
X1163599Y646017D01*
X1163899Y645217D01*
Y641350D01*
G01X1168699Y644950D02*
X1171899D01*
X1171599Y645883D01*
X1171099Y646417D01*
X1170399Y646683D01*
X1169699Y646550D01*
X1169099Y646150D01*
X1168699Y645217D01*
X1168499Y644416D01*
Y643617D01*
X1168699Y642817D01*
X1169199Y642017D01*
X1169799Y641483D01*
X1170499Y641350D01*
X1171199Y641617D01*
X1171899Y642416D01*
G01X1176799Y641350D02*
Y646683D01*
G01Y645617D02*
X1177299Y646150D01*
X1177799Y646550D01*
X1178499Y646683D01*
X1178999Y646550D01*
X1179599Y646150D01*
G01X1184699Y642283D02*
X1185199Y641750D01*
X1185899Y641350D01*
X1186499D01*
X1187099Y641617D01*
X1187499Y642017D01*
X1187699Y642550D01*
X1187599Y643350D01*
X1187199Y643750D01*
X1185399Y644550D01*
X1184999Y645483D01*
X1185199Y646150D01*
X1185599Y646550D01*
X1186199Y646683D01*
X1186799Y646550D01*
X1187399Y646150D01*
G01X1194699Y638683D02*
X1195699Y640017D01*
X1196199Y641350D01*
Y646683D01*
X1195699Y648017D01*
X1194699Y649350D01*
G01X944199Y652850D02*
Y660850D01*
X946599D01*
X947399Y660450D01*
X947999Y659517D01*
X948199Y658450D01*
X947999Y657383D01*
X947499Y656583D01*
X946599Y656183D01*
X944199D01*
G01X954199Y660850D02*
Y652850D01*
G01X951899Y660850D02*
X956499D01*
G01X960099Y652850D02*
Y660850D01*
G01X964299D02*
Y652850D01*
G01Y656850D02*
X960099D01*
G01X968399Y652583D02*
X971999Y660850D01*
G01X975899Y652850D02*
Y660850D01*
X980499Y652850D01*
Y660850D01*
G01X984199Y652850D02*
Y660850D01*
X986599D01*
X987399Y660450D01*
X987999Y659517D01*
X988199Y658450D01*
X987999Y657383D01*
X987499Y656583D01*
X986599Y656183D01*
X984199D01*
G01X994199Y660850D02*
Y652850D01*
G01X991899Y660850D02*
X996499D01*
G01X1000099Y652850D02*
Y660850D01*
G01X1004299D02*
Y652850D01*
G01Y656850D02*
X1000099D01*
G01X1016199Y652850D02*
X1020199Y655517D01*
X1016199Y658183D01*
G01X1024899Y654317D02*
X1027499D01*
G01Y656717D02*
X1024899D01*
G01X1031999Y654050D02*
X1032599Y653383D01*
X1033299Y652983D01*
X1034199Y652850D01*
X1035099Y653117D01*
X1035799Y653650D01*
X1036299Y654583D01*
X1036399Y655650D01*
X1036199Y656717D01*
X1035699Y657383D01*
X1034999Y657917D01*
X1034299Y658050D01*
X1033599Y657917D01*
X1032699Y657383D01*
X1032999Y660850D01*
X1035699D01*
G01X1047199Y652850D02*
Y658183D01*
G01Y656717D02*
X1047499Y657383D01*
X1047999Y657917D01*
X1048699Y658183D01*
X1049399Y657917D01*
X1049899Y657383D01*
X1050199Y656717D01*
Y652850D01*
G01Y656717D02*
X1050499Y657383D01*
X1050999Y657917D01*
X1051699Y658183D01*
X1052399Y657917D01*
X1052899Y657383D01*
X1053199Y656583D01*
Y652850D01*
G01X1055199D02*
Y658183D01*
G01Y656717D02*
X1055499Y657383D01*
X1055999Y657917D01*
X1056699Y658183D01*
X1057399Y657917D01*
X1057899Y657383D01*
X1058199Y656717D01*
Y652850D01*
G01Y656717D02*
X1058499Y657383D01*
X1058999Y657917D01*
X1059699Y658183D01*
X1060399Y657917D01*
X1060899Y657383D01*
X1061199Y656583D01*
Y652850D01*
G01X944399Y665850D02*
Y673850D01*
X948999Y665850D01*
Y673850D01*
G01X952699Y665850D02*
Y673850D01*
X955099D01*
X955899Y673450D01*
X956499Y672517D01*
X956699Y671450D01*
X956499Y670383D01*
X955999Y669583D01*
X955099Y669183D01*
X952699D01*
G01X962699Y673850D02*
Y665850D01*
G01X960399Y673850D02*
X964999D01*
G01X968599Y665850D02*
Y673850D01*
G01X972799D02*
Y665850D01*
G01Y669850D02*
X968599D01*
G01X984599Y666916D02*
X985399Y666250D01*
X986299Y665850D01*
X987099D01*
X987899Y666250D01*
X988499Y666916D01*
X988799Y667850D01*
X988599Y668783D01*
X988099Y669583D01*
X987199Y670117D01*
X985999Y670383D01*
X985299Y670917D01*
X984999Y671850D01*
X985199Y672783D01*
X985699Y673450D01*
X986399Y673850D01*
X987099D01*
X987799Y673583D01*
X988399Y672917D01*
G01X994699Y671183D02*
Y665850D01*
G01Y673317D02*
X994499Y673450D01*
Y673717D01*
X994699Y673850D01*
X994899Y673717D01*
Y673450D01*
X994699Y673317D01*
G01X1001199Y671183D02*
X1004199D01*
X1001199Y665850D01*
X1004199D01*
G01X1009199Y669450D02*
X1012399D01*
X1012099Y670383D01*
X1011599Y670917D01*
X1010899Y671183D01*
X1010199Y671050D01*
X1009599Y670650D01*
X1009199Y669717D01*
X1008999Y668916D01*
Y668117D01*
X1009199Y667317D01*
X1009699Y666517D01*
X1010299Y665983D01*
X1010999Y665850D01*
X1011699Y666117D01*
X1012399Y666916D01*
G01X1024799Y672517D02*
X1025399Y673317D01*
X1026099Y673717D01*
X1026899Y673850D01*
X1027899Y673583D01*
X1028599Y672917D01*
X1028799Y672117D01*
X1028699Y671316D01*
X1028299Y670650D01*
X1026299Y669317D01*
X1025399Y668383D01*
X1024799Y667050D01*
X1024599Y665850D01*
X1028799D01*
G01X1034699Y665583D02*
X1034499Y665717D01*
Y665983D01*
X1034699Y666117D01*
X1034899Y665983D01*
Y665717D01*
X1034699Y665583D01*
G01X1042699Y665850D02*
Y673850D01*
X1041499Y672250D01*
G01Y665850D02*
X1043899D01*
G01X1050699D02*
X1051399Y665983D01*
X1052199Y666383D01*
X1052699Y667050D01*
X1052899Y667983D01*
X1052699Y668916D01*
X1052099Y669717D01*
X1051199Y670117D01*
X1050199D01*
X1049599Y670383D01*
X1049099Y671050D01*
X1048899Y671983D01*
X1049199Y672917D01*
X1049899Y673583D01*
X1050699Y673850D01*
X1051499Y673583D01*
X1052199Y672917D01*
X1052499Y671983D01*
X1052299Y671050D01*
X1051799Y670383D01*
X1051199Y670117D01*
X1050199D01*
X1049299Y669717D01*
X1048699Y668916D01*
X1048499Y667983D01*
X1048699Y667050D01*
X1049199Y666383D01*
X1049999Y665983D01*
X1050699Y665850D01*
G01X1055699D02*
Y671183D01*
G01Y669717D02*
X1055999Y670383D01*
X1056499Y670917D01*
X1057199Y671183D01*
X1057899Y670917D01*
X1058399Y670383D01*
X1058699Y669717D01*
Y665850D01*
G01Y669717D02*
X1058999Y670383D01*
X1059499Y670917D01*
X1060199Y671183D01*
X1060899Y670917D01*
X1061399Y670383D01*
X1061699Y669583D01*
Y665850D01*
G01X1063699D02*
Y671183D01*
G01Y669717D02*
X1063999Y670383D01*
X1064499Y670917D01*
X1065199Y671183D01*
X1065899Y670917D01*
X1066399Y670383D01*
X1066699Y669717D01*
Y665850D01*
G01Y669717D02*
X1066999Y670383D01*
X1067499Y670917D01*
X1068199Y671183D01*
X1068899Y670917D01*
X1069399Y670383D01*
X1069699Y669583D01*
Y665850D01*
G01X1082199Y663183D02*
X1081199Y664517D01*
X1080699Y665850D01*
Y671183D01*
X1081199Y672517D01*
X1082199Y673850D01*
G01X1090699Y665850D02*
X1090099Y665983D01*
X1089499Y666517D01*
X1089099Y667450D01*
X1088899Y668517D01*
X1089099Y669583D01*
X1089499Y670517D01*
X1090099Y671050D01*
X1090699Y671183D01*
X1091299Y671050D01*
X1091899Y670517D01*
X1092299Y669583D01*
X1092399Y668517D01*
X1092299Y667450D01*
X1091899Y666517D01*
X1091299Y665983D01*
X1090699Y665850D01*
G01X1096999D02*
Y671183D01*
G01Y669850D02*
X1097399Y670517D01*
X1097999Y671050D01*
X1098799Y671183D01*
X1099499Y671050D01*
X1100099Y670517D01*
X1100399Y669583D01*
Y665850D01*
G01X1112899D02*
Y673850D01*
G01Y669850D02*
X1113399Y670650D01*
X1113999Y671050D01*
X1114599Y671183D01*
X1115499Y670917D01*
X1116099Y670383D01*
X1116499Y669450D01*
Y668383D01*
X1116299Y667317D01*
X1115899Y666517D01*
X1115199Y665983D01*
X1114599Y665850D01*
X1113999Y665983D01*
X1113399Y666383D01*
X1112899Y667050D01*
G01X1121299Y665850D02*
Y671183D01*
G01Y670117D02*
X1121799Y670650D01*
X1122299Y671050D01*
X1122999Y671183D01*
X1123499Y671050D01*
X1124099Y670650D01*
G01X1129199Y669450D02*
X1132399D01*
X1132099Y670383D01*
X1131599Y670917D01*
X1130899Y671183D01*
X1130199Y671050D01*
X1129599Y670650D01*
X1129199Y669717D01*
X1128999Y668916D01*
Y668117D01*
X1129199Y667317D01*
X1129699Y666517D01*
X1130299Y665983D01*
X1130999Y665850D01*
X1131699Y666117D01*
X1132399Y666916D01*
G01X1140499Y665850D02*
Y671183D01*
G01Y670250D02*
X1140099Y670783D01*
X1139499Y671050D01*
X1138799Y671183D01*
X1138099Y670917D01*
X1137499Y670383D01*
X1137099Y669583D01*
X1136899Y668517D01*
X1137099Y667450D01*
X1137499Y666650D01*
X1138099Y666117D01*
X1138799Y665850D01*
X1139499Y665983D01*
X1140099Y666383D01*
X1140499Y666916D01*
G01X1144999Y665850D02*
Y673850D01*
G01X1148199Y671183D02*
X1144999Y668117D01*
G01X1146299Y669317D02*
X1148399Y665850D01*
G01X1156499D02*
Y671183D01*
G01Y670250D02*
X1156099Y670783D01*
X1155499Y671050D01*
X1154799Y671183D01*
X1154099Y670917D01*
X1153499Y670383D01*
X1153099Y669583D01*
X1152899Y668517D01*
X1153099Y667450D01*
X1153499Y666650D01*
X1154099Y666117D01*
X1154799Y665850D01*
X1155499Y665983D01*
X1156099Y666383D01*
X1156499Y666916D01*
G01X1160199Y671183D02*
X1161399Y665850D01*
X1162699Y671183D01*
X1163999Y665850D01*
X1165199Y671183D01*
G01X1172499Y665850D02*
Y671183D01*
G01Y670250D02*
X1172099Y670783D01*
X1171499Y671050D01*
X1170799Y671183D01*
X1170099Y670917D01*
X1169499Y670383D01*
X1169099Y669583D01*
X1168899Y668517D01*
X1169099Y667450D01*
X1169499Y666650D01*
X1170099Y666117D01*
X1170799Y665850D01*
X1171499Y665983D01*
X1172099Y666383D01*
X1172499Y666916D01*
G01X1176599Y663450D02*
X1177199Y663183D01*
X1177999Y663450D01*
X1178499Y663983D01*
X1178899Y664650D01*
X1179499Y666783D01*
X1180799Y671183D01*
G01X1177599D02*
X1179499Y666783D01*
G01X1187199Y663183D02*
X1188199Y664517D01*
X1188699Y665850D01*
Y671183D01*
X1188199Y672517D01*
X1187199Y673850D01*
G01X944399Y677850D02*
Y685850D01*
X948999Y677850D01*
Y685850D01*
G01X952699Y677850D02*
Y685850D01*
X955099D01*
X955899Y685450D01*
X956499Y684517D01*
X956699Y683450D01*
X956499Y682383D01*
X955999Y681583D01*
X955099Y681183D01*
X952699D01*
G01X962699Y685850D02*
Y677850D01*
G01X960399Y685850D02*
X964999D01*
G01X968599Y677850D02*
Y685850D01*
G01X972799D02*
Y677850D01*
G01Y681850D02*
X968599D01*
G01X984599Y678916D02*
X985399Y678250D01*
X986299Y677850D01*
X987099D01*
X987899Y678250D01*
X988499Y678916D01*
X988799Y679850D01*
X988599Y680783D01*
X988099Y681583D01*
X987199Y682117D01*
X985999Y682383D01*
X985299Y682917D01*
X984999Y683850D01*
X985199Y684783D01*
X985699Y685450D01*
X986399Y685850D01*
X987099D01*
X987799Y685583D01*
X988399Y684917D01*
G01X994699Y683183D02*
Y677850D01*
G01Y685317D02*
X994499Y685450D01*
Y685717D01*
X994699Y685850D01*
X994899Y685717D01*
Y685450D01*
X994699Y685317D01*
G01X1001199Y683183D02*
X1004199D01*
X1001199Y677850D01*
X1004199D01*
G01X1009199Y681450D02*
X1012399D01*
X1012099Y682383D01*
X1011599Y682917D01*
X1010899Y683183D01*
X1010199Y683050D01*
X1009599Y682650D01*
X1009199Y681717D01*
X1008999Y680916D01*
Y680117D01*
X1009199Y679317D01*
X1009699Y678517D01*
X1010299Y677983D01*
X1010999Y677850D01*
X1011699Y678117D01*
X1012399Y678916D01*
G01X1024499Y679450D02*
X1025099Y678517D01*
X1025899Y677983D01*
X1026799Y677850D01*
X1027599Y677983D01*
X1028399Y678650D01*
X1028899Y679450D01*
X1028999Y680250D01*
X1028799Y681183D01*
X1028099Y681850D01*
X1027399Y682117D01*
X1026499D01*
G01X1027399D02*
X1027999Y682517D01*
X1028499Y683183D01*
X1028699Y683983D01*
X1028499Y684783D01*
X1027999Y685450D01*
X1027099Y685850D01*
X1026199Y685717D01*
X1025299Y685183D01*
G01X1034699Y677583D02*
X1034499Y677717D01*
Y677983D01*
X1034699Y678117D01*
X1034899Y677983D01*
Y677717D01*
X1034699Y677583D01*
G01X1040499Y679050D02*
X1041099Y678383D01*
X1041799Y677983D01*
X1042699Y677850D01*
X1043599Y678117D01*
X1044299Y678650D01*
X1044799Y679583D01*
X1044899Y680650D01*
X1044699Y681717D01*
X1044199Y682383D01*
X1043499Y682917D01*
X1042799Y683050D01*
X1042099Y682917D01*
X1041199Y682383D01*
X1041499Y685850D01*
X1044199D01*
G01X1048499Y679050D02*
X1049099Y678383D01*
X1049799Y677983D01*
X1050699Y677850D01*
X1051599Y678117D01*
X1052299Y678650D01*
X1052799Y679583D01*
X1052899Y680650D01*
X1052699Y681717D01*
X1052199Y682383D01*
X1051499Y682917D01*
X1050799Y683050D01*
X1050099Y682917D01*
X1049199Y682383D01*
X1049499Y685850D01*
X1052199D01*
G01X1055699Y677850D02*
Y683183D01*
G01Y681717D02*
X1055999Y682383D01*
X1056499Y682917D01*
X1057199Y683183D01*
X1057899Y682917D01*
X1058399Y682383D01*
X1058699Y681717D01*
Y677850D01*
G01Y681717D02*
X1058999Y682383D01*
X1059499Y682917D01*
X1060199Y683183D01*
X1060899Y682917D01*
X1061399Y682383D01*
X1061699Y681583D01*
Y677850D01*
G01X1063699D02*
Y683183D01*
G01Y681717D02*
X1063999Y682383D01*
X1064499Y682917D01*
X1065199Y683183D01*
X1065899Y682917D01*
X1066399Y682383D01*
X1066699Y681717D01*
Y677850D01*
G01Y681717D02*
X1066999Y682383D01*
X1067499Y682917D01*
X1068199Y683183D01*
X1068899Y682917D01*
X1069399Y682383D01*
X1069699Y681583D01*
Y677850D01*
G01X1082199Y675183D02*
X1081199Y676517D01*
X1080699Y677850D01*
Y683183D01*
X1081199Y684517D01*
X1082199Y685850D01*
G01X1090699Y677850D02*
X1090099Y677983D01*
X1089499Y678517D01*
X1089099Y679450D01*
X1088899Y680517D01*
X1089099Y681583D01*
X1089499Y682517D01*
X1090099Y683050D01*
X1090699Y683183D01*
X1091299Y683050D01*
X1091899Y682517D01*
X1092299Y681583D01*
X1092399Y680517D01*
X1092299Y679450D01*
X1091899Y678517D01*
X1091299Y677983D01*
X1090699Y677850D01*
G01X1096999D02*
Y683183D01*
G01Y681850D02*
X1097399Y682517D01*
X1097999Y683050D01*
X1098799Y683183D01*
X1099499Y683050D01*
X1100099Y682517D01*
X1100399Y681583D01*
Y677850D01*
G01X1112899D02*
Y685850D01*
G01Y681850D02*
X1113399Y682650D01*
X1113999Y683050D01*
X1114599Y683183D01*
X1115499Y682917D01*
X1116099Y682383D01*
X1116499Y681450D01*
Y680383D01*
X1116299Y679317D01*
X1115899Y678517D01*
X1115199Y677983D01*
X1114599Y677850D01*
X1113999Y677983D01*
X1113399Y678383D01*
X1112899Y679050D01*
G01X1121299Y677850D02*
Y683183D01*
G01Y682117D02*
X1121799Y682650D01*
X1122299Y683050D01*
X1122999Y683183D01*
X1123499Y683050D01*
X1124099Y682650D01*
G01X1129199Y681450D02*
X1132399D01*
X1132099Y682383D01*
X1131599Y682917D01*
X1130899Y683183D01*
X1130199Y683050D01*
X1129599Y682650D01*
X1129199Y681717D01*
X1128999Y680916D01*
Y680117D01*
X1129199Y679317D01*
X1129699Y678517D01*
X1130299Y677983D01*
X1130999Y677850D01*
X1131699Y678117D01*
X1132399Y678916D01*
G01X1140499Y677850D02*
Y683183D01*
G01Y682250D02*
X1140099Y682783D01*
X1139499Y683050D01*
X1138799Y683183D01*
X1138099Y682917D01*
X1137499Y682383D01*
X1137099Y681583D01*
X1136899Y680517D01*
X1137099Y679450D01*
X1137499Y678650D01*
X1138099Y678117D01*
X1138799Y677850D01*
X1139499Y677983D01*
X1140099Y678383D01*
X1140499Y678916D01*
G01X1144999Y677850D02*
Y685850D01*
G01X1148199Y683183D02*
X1144999Y680117D01*
G01X1146299Y681317D02*
X1148399Y677850D01*
G01X1156499D02*
Y683183D01*
G01Y682250D02*
X1156099Y682783D01*
X1155499Y683050D01*
X1154799Y683183D01*
X1154099Y682917D01*
X1153499Y682383D01*
X1153099Y681583D01*
X1152899Y680517D01*
X1153099Y679450D01*
X1153499Y678650D01*
X1154099Y678117D01*
X1154799Y677850D01*
X1155499Y677983D01*
X1156099Y678383D01*
X1156499Y678916D01*
G01X1160199Y683183D02*
X1161399Y677850D01*
X1162699Y683183D01*
X1163999Y677850D01*
X1165199Y683183D01*
G01X1172499Y677850D02*
Y683183D01*
G01Y682250D02*
X1172099Y682783D01*
X1171499Y683050D01*
X1170799Y683183D01*
X1170099Y682917D01*
X1169499Y682383D01*
X1169099Y681583D01*
X1168899Y680517D01*
X1169099Y679450D01*
X1169499Y678650D01*
X1170099Y678117D01*
X1170799Y677850D01*
X1171499Y677983D01*
X1172099Y678383D01*
X1172499Y678916D01*
G01X1176599Y675450D02*
X1177199Y675183D01*
X1177999Y675450D01*
X1178499Y675983D01*
X1178899Y676650D01*
X1179499Y678783D01*
X1180799Y683183D01*
G01X1177599D02*
X1179499Y678783D01*
G01X1187199Y675183D02*
X1188199Y676517D01*
X1188699Y677850D01*
Y683183D01*
X1188199Y684517D01*
X1187199Y685850D01*
G01X944399Y691350D02*
Y699350D01*
X948999Y691350D01*
Y699350D01*
G01X952699Y691350D02*
Y699350D01*
X955099D01*
X955899Y698950D01*
X956499Y698017D01*
X956699Y696950D01*
X956499Y695883D01*
X955999Y695083D01*
X955099Y694683D01*
X952699D01*
G01X962699Y699350D02*
Y691350D01*
G01X960399Y699350D02*
X964999D01*
G01X968599Y691350D02*
Y699350D01*
G01X972799D02*
Y691350D01*
G01Y695350D02*
X968599D01*
G01X984599Y692416D02*
X985399Y691750D01*
X986299Y691350D01*
X987099D01*
X987899Y691750D01*
X988499Y692416D01*
X988799Y693350D01*
X988599Y694283D01*
X988099Y695083D01*
X987199Y695617D01*
X985999Y695883D01*
X985299Y696417D01*
X984999Y697350D01*
X985199Y698283D01*
X985699Y698950D01*
X986399Y699350D01*
X987099D01*
X987799Y699083D01*
X988399Y698417D01*
G01X994699Y696683D02*
Y691350D01*
G01Y698817D02*
X994499Y698950D01*
Y699217D01*
X994699Y699350D01*
X994899Y699217D01*
Y698950D01*
X994699Y698817D01*
G01X1001199Y696683D02*
X1004199D01*
X1001199Y691350D01*
X1004199D01*
G01X1009199Y694950D02*
X1012399D01*
X1012099Y695883D01*
X1011599Y696417D01*
X1010899Y696683D01*
X1010199Y696550D01*
X1009599Y696150D01*
X1009199Y695217D01*
X1008999Y694416D01*
Y693617D01*
X1009199Y692817D01*
X1009699Y692017D01*
X1010299Y691483D01*
X1010999Y691350D01*
X1011699Y691617D01*
X1012399Y692416D01*
G01X1020699Y691350D02*
X1016699Y694017D01*
X1020699Y696683D01*
G01X1032499Y692550D02*
X1033099Y691883D01*
X1033799Y691483D01*
X1034699Y691350D01*
X1035599Y691617D01*
X1036299Y692150D01*
X1036799Y693083D01*
X1036899Y694150D01*
X1036699Y695217D01*
X1036199Y695883D01*
X1035499Y696417D01*
X1034799Y696550D01*
X1034099Y696417D01*
X1033199Y695883D01*
X1033499Y699350D01*
X1036199D01*
G01X1039699Y691350D02*
Y696683D01*
G01Y695217D02*
X1039999Y695883D01*
X1040499Y696417D01*
X1041199Y696683D01*
X1041899Y696417D01*
X1042399Y695883D01*
X1042699Y695217D01*
Y691350D01*
G01Y695217D02*
X1042999Y695883D01*
X1043499Y696417D01*
X1044199Y696683D01*
X1044899Y696417D01*
X1045399Y695883D01*
X1045699Y695083D01*
Y691350D01*
G01X1047699D02*
Y696683D01*
G01Y695217D02*
X1047999Y695883D01*
X1048499Y696417D01*
X1049199Y696683D01*
X1049899Y696417D01*
X1050399Y695883D01*
X1050699Y695217D01*
Y691350D01*
G01Y695217D02*
X1050999Y695883D01*
X1051499Y696417D01*
X1052199Y696683D01*
X1052899Y696417D01*
X1053399Y695883D01*
X1053699Y695083D01*
Y691350D01*
G01X1066199Y688683D02*
X1065199Y690017D01*
X1064699Y691350D01*
Y696683D01*
X1065199Y698017D01*
X1066199Y699350D01*
G01X1072999Y691350D02*
Y696683D01*
G01Y695350D02*
X1073399Y696017D01*
X1073999Y696550D01*
X1074799Y696683D01*
X1075499Y696550D01*
X1076099Y696017D01*
X1076399Y695083D01*
Y691350D01*
G01X1082699D02*
X1082099Y691483D01*
X1081499Y692017D01*
X1081099Y692950D01*
X1080899Y694017D01*
X1081099Y695083D01*
X1081499Y696017D01*
X1082099Y696550D01*
X1082699Y696683D01*
X1083299Y696550D01*
X1083899Y696017D01*
X1084299Y695083D01*
X1084399Y694017D01*
X1084299Y692950D01*
X1083899Y692017D01*
X1083299Y691483D01*
X1082699Y691350D01*
G01X1090699Y699350D02*
Y691350D01*
G01X1089299Y696683D02*
X1092099D01*
G01X1106699Y691350D02*
X1106099Y691483D01*
X1105499Y692017D01*
X1105099Y692950D01*
X1104899Y694017D01*
X1105099Y695083D01*
X1105499Y696017D01*
X1106099Y696550D01*
X1106699Y696683D01*
X1107299Y696550D01*
X1107899Y696017D01*
X1108299Y695083D01*
X1108399Y694017D01*
X1108299Y692950D01*
X1107899Y692017D01*
X1107299Y691483D01*
X1106699Y691350D01*
G01X1112999D02*
Y696683D01*
G01Y695350D02*
X1113399Y696017D01*
X1113999Y696550D01*
X1114799Y696683D01*
X1115499Y696550D01*
X1116099Y696017D01*
X1116399Y695083D01*
Y691350D01*
G01X1128899D02*
Y699350D01*
G01Y695350D02*
X1129399Y696150D01*
X1129999Y696550D01*
X1130599Y696683D01*
X1131499Y696417D01*
X1132099Y695883D01*
X1132499Y694950D01*
Y693883D01*
X1132299Y692817D01*
X1131899Y692017D01*
X1131199Y691483D01*
X1130599Y691350D01*
X1129999Y691483D01*
X1129399Y691883D01*
X1128899Y692550D01*
G01X1137299Y691350D02*
Y696683D01*
G01Y695617D02*
X1137799Y696150D01*
X1138299Y696550D01*
X1138999Y696683D01*
X1139499Y696550D01*
X1140099Y696150D01*
G01X1145199Y694950D02*
X1148399D01*
X1148099Y695883D01*
X1147599Y696417D01*
X1146899Y696683D01*
X1146199Y696550D01*
X1145599Y696150D01*
X1145199Y695217D01*
X1144999Y694416D01*
Y693617D01*
X1145199Y692817D01*
X1145699Y692017D01*
X1146299Y691483D01*
X1146999Y691350D01*
X1147699Y691617D01*
X1148399Y692416D01*
G01X1156499Y691350D02*
Y696683D01*
G01Y695750D02*
X1156099Y696283D01*
X1155499Y696550D01*
X1154799Y696683D01*
X1154099Y696417D01*
X1153499Y695883D01*
X1153099Y695083D01*
X1152899Y694017D01*
X1153099Y692950D01*
X1153499Y692150D01*
X1154099Y691617D01*
X1154799Y691350D01*
X1155499Y691483D01*
X1156099Y691883D01*
X1156499Y692416D01*
G01X1160999Y691350D02*
Y699350D01*
G01X1164199Y696683D02*
X1160999Y693617D01*
G01X1162299Y694817D02*
X1164399Y691350D01*
G01X1172499D02*
Y696683D01*
G01Y695750D02*
X1172099Y696283D01*
X1171499Y696550D01*
X1170799Y696683D01*
X1170099Y696417D01*
X1169499Y695883D01*
X1169099Y695083D01*
X1168899Y694017D01*
X1169099Y692950D01*
X1169499Y692150D01*
X1170099Y691617D01*
X1170799Y691350D01*
X1171499Y691483D01*
X1172099Y691883D01*
X1172499Y692416D01*
G01X1176199Y696683D02*
X1177399Y691350D01*
X1178699Y696683D01*
X1179999Y691350D01*
X1181199Y696683D01*
G01X1188499Y691350D02*
Y696683D01*
G01Y695750D02*
X1188099Y696283D01*
X1187499Y696550D01*
X1186799Y696683D01*
X1186099Y696417D01*
X1185499Y695883D01*
X1185099Y695083D01*
X1184899Y694017D01*
X1185099Y692950D01*
X1185499Y692150D01*
X1186099Y691617D01*
X1186799Y691350D01*
X1187499Y691483D01*
X1188099Y691883D01*
X1188499Y692416D01*
G01X1192599Y688950D02*
X1193199Y688683D01*
X1193999Y688950D01*
X1194499Y689483D01*
X1194899Y690150D01*
X1195499Y692283D01*
X1196799Y696683D01*
G01X1193599D02*
X1195499Y692283D01*
G01X1203199Y688683D02*
X1204199Y690017D01*
X1204699Y691350D01*
Y696683D01*
X1204199Y698017D01*
X1203199Y699350D01*
G01X945199Y702683D02*
X944199Y704017D01*
X943699Y705350D01*
Y710683D01*
X944199Y712017D01*
X945199Y713350D01*
G01X951599Y706416D02*
X952399Y705750D01*
X953299Y705350D01*
X954099D01*
X954899Y705750D01*
X955499Y706416D01*
X955799Y707350D01*
X955599Y708283D01*
X955099Y709083D01*
X954199Y709617D01*
X952999Y709883D01*
X952299Y710417D01*
X951999Y711350D01*
X952199Y712283D01*
X952699Y712950D01*
X953399Y713350D01*
X954099D01*
X954799Y713083D01*
X955399Y712417D01*
G01X959999Y710683D02*
Y706950D01*
X960399Y706017D01*
X960999Y705483D01*
X961699Y705350D01*
X962399Y705483D01*
X962999Y706017D01*
X963399Y706950D01*
G01Y705350D02*
Y710683D01*
G01X968299Y705350D02*
Y710683D01*
G01Y709617D02*
X968799Y710150D01*
X969299Y710550D01*
X969999Y710683D01*
X970499Y710550D01*
X971099Y710150D01*
G01X977099Y705350D02*
Y712150D01*
X977299Y712817D01*
X977699Y713217D01*
X978299Y713350D01*
X978899Y713083D01*
X979199Y712417D01*
G01X977999Y710150D02*
X975999D01*
G01X987499Y705350D02*
Y710683D01*
G01Y709750D02*
X987099Y710283D01*
X986499Y710550D01*
X985799Y710683D01*
X985099Y710417D01*
X984499Y709883D01*
X984099Y709083D01*
X983899Y708017D01*
X984099Y706950D01*
X984499Y706150D01*
X985099Y705617D01*
X985799Y705350D01*
X986499Y705483D01*
X987099Y705883D01*
X987499Y706416D01*
G01X995299Y710017D02*
X994599Y710550D01*
X993999Y710683D01*
X993199Y710417D01*
X992599Y709883D01*
X992199Y708950D01*
X992099Y708017D01*
X992199Y707083D01*
X992599Y706283D01*
X993199Y705617D01*
X993999Y705350D01*
X994699Y705617D01*
X995299Y706150D01*
G01X1000199Y708950D02*
X1003399D01*
X1003099Y709883D01*
X1002599Y710417D01*
X1001899Y710683D01*
X1001199Y710550D01*
X1000599Y710150D01*
X1000199Y709217D01*
X999999Y708416D01*
Y707617D01*
X1000199Y706817D01*
X1000699Y706017D01*
X1001299Y705483D01*
X1001999Y705350D01*
X1002699Y705617D01*
X1003399Y706416D01*
G01X1017699Y713350D02*
Y705350D01*
G01X1016299Y710683D02*
X1019099D01*
G01X1024299Y705350D02*
Y710683D01*
G01Y709617D02*
X1024799Y710150D01*
X1025299Y710550D01*
X1025999Y710683D01*
X1026499Y710550D01*
X1027099Y710150D01*
G01X1032199Y708950D02*
X1035399D01*
X1035099Y709883D01*
X1034599Y710417D01*
X1033899Y710683D01*
X1033199Y710550D01*
X1032599Y710150D01*
X1032199Y709217D01*
X1031999Y708416D01*
Y707617D01*
X1032199Y706817D01*
X1032699Y706017D01*
X1033299Y705483D01*
X1033999Y705350D01*
X1034699Y705617D01*
X1035399Y706416D01*
G01X1043499Y705350D02*
Y710683D01*
G01Y709750D02*
X1043099Y710283D01*
X1042499Y710550D01*
X1041799Y710683D01*
X1041099Y710417D01*
X1040499Y709883D01*
X1040099Y709083D01*
X1039899Y708017D01*
X1040099Y706950D01*
X1040499Y706150D01*
X1041099Y705617D01*
X1041799Y705350D01*
X1042499Y705483D01*
X1043099Y705883D01*
X1043499Y706416D01*
G01X1049699Y713350D02*
Y705350D01*
G01X1048299Y710683D02*
X1051099D01*
G01X1054699Y705350D02*
Y710683D01*
G01Y709217D02*
X1054999Y709883D01*
X1055499Y710417D01*
X1056199Y710683D01*
X1056899Y710417D01*
X1057399Y709883D01*
X1057699Y709217D01*
Y705350D01*
G01Y709217D02*
X1057999Y709883D01*
X1058499Y710417D01*
X1059199Y710683D01*
X1059899Y710417D01*
X1060399Y709883D01*
X1060699Y709083D01*
Y705350D01*
G01X1064199Y708950D02*
X1067399D01*
X1067099Y709883D01*
X1066599Y710417D01*
X1065899Y710683D01*
X1065199Y710550D01*
X1064599Y710150D01*
X1064199Y709217D01*
X1063999Y708416D01*
Y707617D01*
X1064199Y706817D01*
X1064699Y706017D01*
X1065299Y705483D01*
X1065999Y705350D01*
X1066699Y705617D01*
X1067399Y706416D01*
G01X1071999Y705350D02*
Y710683D01*
G01Y709350D02*
X1072399Y710017D01*
X1072999Y710550D01*
X1073799Y710683D01*
X1074499Y710550D01*
X1075099Y710017D01*
X1075399Y709083D01*
Y705350D01*
G01X1081699Y713350D02*
Y705350D01*
G01X1080299Y710683D02*
X1083099D01*
G01X1097699D02*
Y705350D01*
G01Y712817D02*
X1097499Y712950D01*
Y713217D01*
X1097699Y713350D01*
X1097899Y713217D01*
Y712950D01*
X1097699Y712817D01*
G01X1104199Y706283D02*
X1104699Y705750D01*
X1105399Y705350D01*
X1105999D01*
X1106599Y705617D01*
X1106999Y706017D01*
X1107199Y706550D01*
X1107099Y707350D01*
X1106699Y707750D01*
X1104899Y708550D01*
X1104499Y709483D01*
X1104699Y710150D01*
X1105099Y710550D01*
X1105699Y710683D01*
X1106299Y710550D01*
X1106899Y710150D01*
G01X1119599Y705350D02*
Y713350D01*
G01X1123799D02*
Y705350D01*
G01Y709350D02*
X1119599D01*
G01X1127199Y705350D02*
X1129699Y713350D01*
X1132199Y705350D01*
G01X1131299Y708150D02*
X1128099D01*
G01X1135599Y706416D02*
X1136399Y705750D01*
X1137299Y705350D01*
X1138099D01*
X1138899Y705750D01*
X1139499Y706416D01*
X1139799Y707350D01*
X1139599Y708283D01*
X1139099Y709083D01*
X1138199Y709617D01*
X1136999Y709883D01*
X1136299Y710417D01*
X1135999Y711350D01*
X1136199Y712283D01*
X1136699Y712950D01*
X1137399Y713350D01*
X1138099D01*
X1138799Y713083D01*
X1139399Y712417D01*
G01X1143699Y713350D02*
Y705350D01*
X1147699D01*
G01X1161699D02*
X1161099Y705483D01*
X1160499Y706017D01*
X1160099Y706950D01*
X1159899Y708017D01*
X1160099Y709083D01*
X1160499Y710017D01*
X1161099Y710550D01*
X1161699Y710683D01*
X1162299Y710550D01*
X1162899Y710017D01*
X1163299Y709083D01*
X1163399Y708017D01*
X1163299Y706950D01*
X1162899Y706017D01*
X1162299Y705483D01*
X1161699Y705350D01*
G01X1168299D02*
Y710683D01*
G01Y709617D02*
X1168799Y710150D01*
X1169299Y710550D01*
X1169999Y710683D01*
X1170499Y710550D01*
X1171099Y710150D01*
G01X1183699Y713350D02*
Y705350D01*
X1187699D01*
G01X1192199Y708950D02*
X1195399D01*
X1195099Y709883D01*
X1194599Y710417D01*
X1193899Y710683D01*
X1193199Y710550D01*
X1192599Y710150D01*
X1192199Y709217D01*
X1191999Y708416D01*
Y707617D01*
X1192199Y706817D01*
X1192699Y706017D01*
X1193299Y705483D01*
X1193999Y705350D01*
X1194699Y705617D01*
X1195399Y706416D01*
G01X1203499Y705350D02*
Y710683D01*
G01Y709750D02*
X1203099Y710283D01*
X1202499Y710550D01*
X1201799Y710683D01*
X1201099Y710417D01*
X1200499Y709883D01*
X1200099Y709083D01*
X1199899Y708017D01*
X1200099Y706950D01*
X1200499Y706150D01*
X1201099Y705617D01*
X1201799Y705350D01*
X1202499Y705483D01*
X1203099Y705883D01*
X1203499Y706416D01*
G01X1211499Y713350D02*
Y705350D01*
G01Y706550D02*
X1211099Y705883D01*
X1210499Y705483D01*
X1209799Y705350D01*
X1208999Y705617D01*
X1208399Y706283D01*
X1207999Y707083D01*
X1207899Y708017D01*
X1207999Y708950D01*
X1208399Y709750D01*
X1208999Y710417D01*
X1209799Y710683D01*
X1210499Y710550D01*
X1210999Y710283D01*
X1211499Y709750D01*
G01X1223799Y705350D02*
Y713350D01*
X1227599D01*
G01X1226199Y709483D02*
X1223799D01*
G01X1232299Y705350D02*
Y710683D01*
G01Y709617D02*
X1232799Y710150D01*
X1233299Y710550D01*
X1233999Y710683D01*
X1234499Y710550D01*
X1235099Y710150D01*
G01X1240199Y708950D02*
X1243399D01*
X1243099Y709883D01*
X1242599Y710417D01*
X1241899Y710683D01*
X1241199Y710550D01*
X1240599Y710150D01*
X1240199Y709217D01*
X1239999Y708416D01*
Y707617D01*
X1240199Y706817D01*
X1240699Y706017D01*
X1241299Y705483D01*
X1241999Y705350D01*
X1242699Y705617D01*
X1243399Y706416D01*
G01X1248199Y708950D02*
X1251399D01*
X1251099Y709883D01*
X1250599Y710417D01*
X1249899Y710683D01*
X1249199Y710550D01*
X1248599Y710150D01*
X1248199Y709217D01*
X1247999Y708416D01*
Y707617D01*
X1248199Y706817D01*
X1248699Y706017D01*
X1249299Y705483D01*
X1249999Y705350D01*
X1250699Y705617D01*
X1251399Y706416D01*
G01X1263599Y705350D02*
Y713350D01*
G01X1267799D02*
Y705350D01*
G01Y709350D02*
X1263599D01*
G01X1271199Y705350D02*
X1273699Y713350D01*
X1276199Y705350D01*
G01X1275299Y708150D02*
X1272099D01*
G01X1279599Y706416D02*
X1280399Y705750D01*
X1281299Y705350D01*
X1282099D01*
X1282899Y705750D01*
X1283499Y706416D01*
X1283799Y707350D01*
X1283599Y708283D01*
X1283099Y709083D01*
X1282199Y709617D01*
X1280999Y709883D01*
X1280299Y710417D01*
X1279999Y711350D01*
X1280199Y712283D01*
X1280699Y712950D01*
X1281399Y713350D01*
X1282099D01*
X1282799Y713083D01*
X1283399Y712417D01*
G01X1287699Y713350D02*
Y705350D01*
X1291699D01*
G01X1298199Y702683D02*
X1299199Y704017D01*
X1299699Y705350D01*
Y710683D01*
X1299199Y712017D01*
X1298199Y713350D01*
G01X944199Y725683D02*
X943199Y727017D01*
X942699Y728350D01*
Y733683D01*
X943199Y735017D01*
X944199Y736350D01*
G01X950599Y729416D02*
X951399Y728750D01*
X952299Y728350D01*
X953099D01*
X953899Y728750D01*
X954499Y729416D01*
X954799Y730350D01*
X954599Y731283D01*
X954099Y732083D01*
X953199Y732617D01*
X951999Y732883D01*
X951299Y733417D01*
X950999Y734350D01*
X951199Y735283D01*
X951699Y735950D01*
X952399Y736350D01*
X953099D01*
X953799Y736083D01*
X954399Y735417D01*
G01X958999Y733683D02*
Y729950D01*
X959399Y729017D01*
X959999Y728483D01*
X960699Y728350D01*
X961399Y728483D01*
X961999Y729017D01*
X962399Y729950D01*
G01Y728350D02*
Y733683D01*
G01X967299Y728350D02*
Y733683D01*
G01Y732617D02*
X967799Y733150D01*
X968299Y733550D01*
X968999Y733683D01*
X969499Y733550D01*
X970099Y733150D01*
G01X976099Y728350D02*
Y735150D01*
X976299Y735817D01*
X976699Y736217D01*
X977299Y736350D01*
X977899Y736083D01*
X978199Y735417D01*
G01X976999Y733150D02*
X974999D01*
G01X986499Y728350D02*
Y733683D01*
G01Y732750D02*
X986099Y733283D01*
X985499Y733550D01*
X984799Y733683D01*
X984099Y733417D01*
X983499Y732883D01*
X983099Y732083D01*
X982899Y731017D01*
X983099Y729950D01*
X983499Y729150D01*
X984099Y728617D01*
X984799Y728350D01*
X985499Y728483D01*
X986099Y728883D01*
X986499Y729416D01*
G01X994299Y733017D02*
X993599Y733550D01*
X992999Y733683D01*
X992199Y733417D01*
X991599Y732883D01*
X991199Y731950D01*
X991099Y731017D01*
X991199Y730083D01*
X991599Y729283D01*
X992199Y728617D01*
X992999Y728350D01*
X993699Y728617D01*
X994299Y729150D01*
G01X999199Y731950D02*
X1002399D01*
X1002099Y732883D01*
X1001599Y733417D01*
X1000899Y733683D01*
X1000199Y733550D01*
X999599Y733150D01*
X999199Y732217D01*
X998999Y731416D01*
Y730617D01*
X999199Y729817D01*
X999699Y729017D01*
X1000299Y728483D01*
X1000999Y728350D01*
X1001699Y728617D01*
X1002399Y729416D01*
G01X1016699Y736350D02*
Y728350D01*
G01X1015299Y733683D02*
X1018099D01*
G01X1023299Y728350D02*
Y733683D01*
G01Y732617D02*
X1023799Y733150D01*
X1024299Y733550D01*
X1024999Y733683D01*
X1025499Y733550D01*
X1026099Y733150D01*
G01X1031199Y731950D02*
X1034399D01*
X1034099Y732883D01*
X1033599Y733417D01*
X1032899Y733683D01*
X1032199Y733550D01*
X1031599Y733150D01*
X1031199Y732217D01*
X1030999Y731416D01*
Y730617D01*
X1031199Y729817D01*
X1031699Y729017D01*
X1032299Y728483D01*
X1032999Y728350D01*
X1033699Y728617D01*
X1034399Y729416D01*
G01X1042499Y728350D02*
Y733683D01*
G01Y732750D02*
X1042099Y733283D01*
X1041499Y733550D01*
X1040799Y733683D01*
X1040099Y733417D01*
X1039499Y732883D01*
X1039099Y732083D01*
X1038899Y731017D01*
X1039099Y729950D01*
X1039499Y729150D01*
X1040099Y728617D01*
X1040799Y728350D01*
X1041499Y728483D01*
X1042099Y728883D01*
X1042499Y729416D01*
G01X1048699Y736350D02*
Y728350D01*
G01X1047299Y733683D02*
X1050099D01*
G01X1053699Y728350D02*
Y733683D01*
G01Y732217D02*
X1053999Y732883D01*
X1054499Y733417D01*
X1055199Y733683D01*
X1055899Y733417D01*
X1056399Y732883D01*
X1056699Y732217D01*
Y728350D01*
G01Y732217D02*
X1056999Y732883D01*
X1057499Y733417D01*
X1058199Y733683D01*
X1058899Y733417D01*
X1059399Y732883D01*
X1059699Y732083D01*
Y728350D01*
G01X1063199Y731950D02*
X1066399D01*
X1066099Y732883D01*
X1065599Y733417D01*
X1064899Y733683D01*
X1064199Y733550D01*
X1063599Y733150D01*
X1063199Y732217D01*
X1062999Y731416D01*
Y730617D01*
X1063199Y729817D01*
X1063699Y729017D01*
X1064299Y728483D01*
X1064999Y728350D01*
X1065699Y728617D01*
X1066399Y729416D01*
G01X1070999Y728350D02*
Y733683D01*
G01Y732350D02*
X1071399Y733017D01*
X1071999Y733550D01*
X1072799Y733683D01*
X1073499Y733550D01*
X1074099Y733017D01*
X1074399Y732083D01*
Y728350D01*
G01X1080699Y736350D02*
Y728350D01*
G01X1079299Y733683D02*
X1082099D01*
G01X1096699D02*
Y728350D01*
G01Y735817D02*
X1096499Y735950D01*
Y736217D01*
X1096699Y736350D01*
X1096899Y736217D01*
Y735950D01*
X1096699Y735817D01*
G01X1103199Y729283D02*
X1103699Y728750D01*
X1104399Y728350D01*
X1104999D01*
X1105599Y728617D01*
X1105999Y729017D01*
X1106199Y729550D01*
X1106099Y730350D01*
X1105699Y730750D01*
X1103899Y731550D01*
X1103499Y732483D01*
X1103699Y733150D01*
X1104099Y733550D01*
X1104699Y733683D01*
X1105299Y733550D01*
X1105899Y733150D01*
G01X1120699Y733683D02*
Y728350D01*
G01Y735817D02*
X1120499Y735950D01*
Y736217D01*
X1120699Y736350D01*
X1120899Y736217D01*
Y735950D01*
X1120699Y735817D01*
G01X1125699Y728350D02*
Y733683D01*
G01Y732217D02*
X1125999Y732883D01*
X1126499Y733417D01*
X1127199Y733683D01*
X1127899Y733417D01*
X1128399Y732883D01*
X1128699Y732217D01*
Y728350D01*
G01Y732217D02*
X1128999Y732883D01*
X1129499Y733417D01*
X1130199Y733683D01*
X1130899Y733417D01*
X1131399Y732883D01*
X1131699Y732083D01*
Y728350D01*
G01X1133699D02*
Y733683D01*
G01Y732217D02*
X1133999Y732883D01*
X1134499Y733417D01*
X1135199Y733683D01*
X1135899Y733417D01*
X1136399Y732883D01*
X1136699Y732217D01*
Y728350D01*
G01Y732217D02*
X1136999Y732883D01*
X1137499Y733417D01*
X1138199Y733683D01*
X1138899Y733417D01*
X1139399Y732883D01*
X1139699Y732083D01*
Y728350D01*
G01X1143199Y731950D02*
X1146399D01*
X1146099Y732883D01*
X1145599Y733417D01*
X1144899Y733683D01*
X1144199Y733550D01*
X1143599Y733150D01*
X1143199Y732217D01*
X1142999Y731416D01*
Y730617D01*
X1143199Y729817D01*
X1143699Y729017D01*
X1144299Y728483D01*
X1144999Y728350D01*
X1145699Y728617D01*
X1146399Y729416D01*
G01X1151299Y728350D02*
Y733683D01*
G01Y732617D02*
X1151799Y733150D01*
X1152299Y733550D01*
X1152999Y733683D01*
X1153499Y733550D01*
X1154099Y733150D01*
G01X1159199Y729283D02*
X1159699Y728750D01*
X1160399Y728350D01*
X1160999D01*
X1161599Y728617D01*
X1161999Y729017D01*
X1162199Y729550D01*
X1162099Y730350D01*
X1161699Y730750D01*
X1159899Y731550D01*
X1159499Y732483D01*
X1159699Y733150D01*
X1160099Y733550D01*
X1160699Y733683D01*
X1161299Y733550D01*
X1161899Y733150D01*
G01X1168699Y733683D02*
Y728350D01*
G01Y735817D02*
X1168499Y735950D01*
Y736217D01*
X1168699Y736350D01*
X1168899Y736217D01*
Y735950D01*
X1168699Y735817D01*
G01X1176699Y728350D02*
X1176099Y728483D01*
X1175499Y729017D01*
X1175099Y729950D01*
X1174899Y731017D01*
X1175099Y732083D01*
X1175499Y733017D01*
X1176099Y733550D01*
X1176699Y733683D01*
X1177299Y733550D01*
X1177899Y733017D01*
X1178299Y732083D01*
X1178399Y731017D01*
X1178299Y729950D01*
X1177899Y729017D01*
X1177299Y728483D01*
X1176699Y728350D01*
G01X1182999D02*
Y733683D01*
G01Y732350D02*
X1183399Y733017D01*
X1183999Y733550D01*
X1184799Y733683D01*
X1185499Y733550D01*
X1186099Y733017D01*
X1186399Y732083D01*
Y728350D01*
G01X1201299Y732350D02*
X1203299D01*
Y729950D01*
X1202699Y729150D01*
X1201999Y728617D01*
X1200999Y728350D01*
X1199999Y728617D01*
X1199299Y729150D01*
X1198699Y729950D01*
X1198299Y730883D01*
X1198099Y731950D01*
Y732883D01*
X1198299Y733683D01*
X1198699Y734617D01*
X1199299Y735417D01*
X1199899Y735950D01*
X1200699Y736350D01*
X1201399D01*
X1202199Y736083D01*
X1202799Y735550D01*
G01X1208699Y728350D02*
X1208099Y728483D01*
X1207499Y729017D01*
X1207099Y729950D01*
X1206899Y731017D01*
X1207099Y732083D01*
X1207499Y733017D01*
X1208099Y733550D01*
X1208699Y733683D01*
X1209299Y733550D01*
X1209899Y733017D01*
X1210299Y732083D01*
X1210399Y731017D01*
X1210299Y729950D01*
X1209899Y729017D01*
X1209299Y728483D01*
X1208699Y728350D01*
G01X1216699D02*
Y736350D01*
G01X1226499D02*
Y728350D01*
G01Y729550D02*
X1226099Y728883D01*
X1225499Y728483D01*
X1224799Y728350D01*
X1223999Y728617D01*
X1223399Y729283D01*
X1222999Y730083D01*
X1222899Y731017D01*
X1222999Y731950D01*
X1223399Y732750D01*
X1223999Y733417D01*
X1224799Y733683D01*
X1225499Y733550D01*
X1225999Y733283D01*
X1226499Y732750D01*
G01X1232499Y726883D02*
X1232899Y728617D01*
G01X1242699Y728350D02*
X1238699D01*
Y736350D01*
X1242699D01*
G01X1241099Y732483D02*
X1238699D01*
G01X1246999Y728350D02*
Y733683D01*
G01Y732350D02*
X1247399Y733017D01*
X1247999Y733550D01*
X1248799Y733683D01*
X1249499Y733550D01*
X1250099Y733017D01*
X1250399Y732083D01*
Y728350D01*
G01X1256699Y736350D02*
Y728350D01*
G01X1255299Y733683D02*
X1258099D01*
G01X1263199Y731950D02*
X1266399D01*
X1266099Y732883D01*
X1265599Y733417D01*
X1264899Y733683D01*
X1264199Y733550D01*
X1263599Y733150D01*
X1263199Y732217D01*
X1262999Y731416D01*
Y730617D01*
X1263199Y729817D01*
X1263699Y729017D01*
X1264299Y728483D01*
X1264999Y728350D01*
X1265699Y728617D01*
X1266399Y729416D01*
G01X1270999Y728350D02*
Y736350D01*
G01X1274199Y733683D02*
X1270999Y730617D01*
G01X1272299Y731817D02*
X1274399Y728350D01*
G01X1288699D02*
X1288099Y728483D01*
X1287499Y729017D01*
X1287099Y729950D01*
X1286899Y731017D01*
X1287099Y732083D01*
X1287499Y733017D01*
X1288099Y733550D01*
X1288699Y733683D01*
X1289299Y733550D01*
X1289899Y733017D01*
X1290299Y732083D01*
X1290399Y731017D01*
X1290299Y729950D01*
X1289899Y729017D01*
X1289299Y728483D01*
X1288699Y728350D01*
G01X1295299D02*
Y733683D01*
G01Y732617D02*
X1295799Y733150D01*
X1296299Y733550D01*
X1296999Y733683D01*
X1297499Y733550D01*
X1298099Y733150D01*
G01X1311499Y736350D02*
X1313899D01*
G01X1312699D02*
Y728350D01*
G01X1311499D02*
X1313899D01*
G01X1317699D02*
Y733683D01*
G01Y732217D02*
X1317999Y732883D01*
X1318499Y733417D01*
X1319199Y733683D01*
X1319899Y733417D01*
X1320399Y732883D01*
X1320699Y732217D01*
Y728350D01*
G01Y732217D02*
X1320999Y732883D01*
X1321499Y733417D01*
X1322199Y733683D01*
X1322899Y733417D01*
X1323399Y732883D01*
X1323699Y732083D01*
Y728350D01*
G01X1326199D02*
X1328699Y736350D01*
X1331199Y728350D01*
G01X1330299Y731150D02*
X1327099D01*
G01X1335299Y726350D02*
X1335999Y725817D01*
X1336799Y725683D01*
X1337499Y725817D01*
X1338099Y726483D01*
X1338499Y727417D01*
Y733683D01*
G01Y732617D02*
X1338099Y733150D01*
X1337499Y733550D01*
X1336799Y733683D01*
X1335999Y733417D01*
X1335499Y732883D01*
X1335099Y731950D01*
X1334899Y731017D01*
X1334999Y730217D01*
X1335399Y729283D01*
X1335999Y728617D01*
X1336799Y728350D01*
X1337399Y728483D01*
X1338099Y729017D01*
X1338499Y729550D01*
G01X1345199Y725683D02*
X1346199Y727017D01*
X1346699Y728350D01*
Y733683D01*
X1346199Y735017D01*
X1345199Y736350D01*
G01X944699Y716350D02*
Y724350D01*
X947099D01*
X947899Y723950D01*
X948499Y723017D01*
X948699Y721950D01*
X948499Y720883D01*
X947999Y720083D01*
X947099Y719683D01*
X944699D01*
G01X954699Y724350D02*
Y716350D01*
G01X952399Y724350D02*
X956999D01*
G01X960599Y716350D02*
Y724350D01*
G01X964799D02*
Y716350D01*
G01Y720350D02*
X960599D01*
G01X976999Y716350D02*
Y724350D01*
G01Y720483D02*
X977499Y721150D01*
X977999Y721550D01*
X978799Y721683D01*
X979399Y721550D01*
X980099Y721017D01*
X980399Y720217D01*
Y716350D01*
G01X986699D02*
X986099Y716483D01*
X985499Y717017D01*
X985099Y717950D01*
X984899Y719017D01*
X985099Y720083D01*
X985499Y721017D01*
X986099Y721550D01*
X986699Y721683D01*
X987299Y721550D01*
X987899Y721017D01*
X988299Y720083D01*
X988399Y719017D01*
X988299Y717950D01*
X987899Y717017D01*
X987299Y716483D01*
X986699Y716350D01*
G01X994699D02*
Y724350D01*
G01X1001199Y719950D02*
X1004399D01*
X1004099Y720883D01*
X1003599Y721417D01*
X1002899Y721683D01*
X1002199Y721550D01*
X1001599Y721150D01*
X1001199Y720217D01*
X1000999Y719416D01*
Y718617D01*
X1001199Y717817D01*
X1001699Y717017D01*
X1002299Y716483D01*
X1002999Y716350D01*
X1003699Y716617D01*
X1004399Y717416D01*
G01X1018099Y716350D02*
Y723150D01*
X1018299Y723817D01*
X1018699Y724217D01*
X1019299Y724350D01*
X1019899Y724083D01*
X1020199Y723417D01*
G01X1018999Y721150D02*
X1016999D01*
G01X1026699Y716350D02*
X1026099Y716483D01*
X1025499Y717017D01*
X1025099Y717950D01*
X1024899Y719017D01*
X1025099Y720083D01*
X1025499Y721017D01*
X1026099Y721550D01*
X1026699Y721683D01*
X1027299Y721550D01*
X1027899Y721017D01*
X1028299Y720083D01*
X1028399Y719017D01*
X1028299Y717950D01*
X1027899Y717017D01*
X1027299Y716483D01*
X1026699Y716350D01*
G01X1033299D02*
Y721683D01*
G01Y720617D02*
X1033799Y721150D01*
X1034299Y721550D01*
X1034999Y721683D01*
X1035499Y721550D01*
X1036099Y721150D01*
G01X1052299Y721017D02*
X1051599Y721550D01*
X1050999Y721683D01*
X1050199Y721417D01*
X1049599Y720883D01*
X1049199Y719950D01*
X1049099Y719017D01*
X1049199Y718083D01*
X1049599Y717283D01*
X1050199Y716617D01*
X1050999Y716350D01*
X1051699Y716617D01*
X1052299Y717150D01*
G01X1058699Y716350D02*
X1058099Y716483D01*
X1057499Y717017D01*
X1057099Y717950D01*
X1056899Y719017D01*
X1057099Y720083D01*
X1057499Y721017D01*
X1058099Y721550D01*
X1058699Y721683D01*
X1059299Y721550D01*
X1059899Y721017D01*
X1060299Y720083D01*
X1060399Y719017D01*
X1060299Y717950D01*
X1059899Y717017D01*
X1059299Y716483D01*
X1058699Y716350D01*
G01X1063699D02*
Y721683D01*
G01Y720217D02*
X1063999Y720883D01*
X1064499Y721417D01*
X1065199Y721683D01*
X1065899Y721417D01*
X1066399Y720883D01*
X1066699Y720217D01*
Y716350D01*
G01Y720217D02*
X1066999Y720883D01*
X1067499Y721417D01*
X1068199Y721683D01*
X1068899Y721417D01*
X1069399Y720883D01*
X1069699Y720083D01*
Y716350D01*
G01X1072899Y713683D02*
Y721683D01*
G01Y720483D02*
X1073399Y721150D01*
X1073899Y721550D01*
X1074699Y721683D01*
X1075399Y721550D01*
X1076099Y720883D01*
X1076399Y719950D01*
X1076499Y719017D01*
X1076399Y718083D01*
X1076099Y717150D01*
X1075499Y716617D01*
X1074699Y716350D01*
X1073999Y716483D01*
X1073299Y716883D01*
X1072899Y717416D01*
G01X1082699Y716350D02*
X1082099Y716483D01*
X1081499Y717017D01*
X1081099Y717950D01*
X1080899Y719017D01*
X1081099Y720083D01*
X1081499Y721017D01*
X1082099Y721550D01*
X1082699Y721683D01*
X1083299Y721550D01*
X1083899Y721017D01*
X1084299Y720083D01*
X1084399Y719017D01*
X1084299Y717950D01*
X1083899Y717017D01*
X1083299Y716483D01*
X1082699Y716350D01*
G01X1088999D02*
Y721683D01*
G01Y720350D02*
X1089399Y721017D01*
X1089999Y721550D01*
X1090799Y721683D01*
X1091499Y721550D01*
X1092099Y721017D01*
X1092399Y720083D01*
Y716350D01*
G01X1097199Y719950D02*
X1100399D01*
X1100099Y720883D01*
X1099599Y721417D01*
X1098899Y721683D01*
X1098199Y721550D01*
X1097599Y721150D01*
X1097199Y720217D01*
X1096999Y719416D01*
Y718617D01*
X1097199Y717817D01*
X1097699Y717017D01*
X1098299Y716483D01*
X1098999Y716350D01*
X1099699Y716617D01*
X1100399Y717416D01*
G01X1104999Y716350D02*
Y721683D01*
G01Y720350D02*
X1105399Y721017D01*
X1105999Y721550D01*
X1106799Y721683D01*
X1107499Y721550D01*
X1108099Y721017D01*
X1108399Y720083D01*
Y716350D01*
G01X1114699Y724350D02*
Y716350D01*
G01X1113299Y721683D02*
X1116099D01*
G01X1130199Y713683D02*
X1129199Y715017D01*
X1128699Y716350D01*
Y721683D01*
X1129199Y723017D01*
X1130199Y724350D01*
G01X1138699Y716350D02*
Y724350D01*
X1137499Y722750D01*
G01Y716350D02*
X1139899D01*
G01X1144799Y719683D02*
X1145499Y720617D01*
X1146099Y721150D01*
X1146899Y721417D01*
X1147599Y721150D01*
X1148099Y720617D01*
X1148499Y719817D01*
X1148599Y718883D01*
X1148499Y718083D01*
X1148099Y717283D01*
X1147499Y716617D01*
X1146799Y716350D01*
X1145999Y716617D01*
X1145299Y717416D01*
X1144899Y718617D01*
X1144799Y719950D01*
X1144999Y721683D01*
X1145299Y722617D01*
X1145799Y723550D01*
X1146499Y724217D01*
X1147199Y724350D01*
X1147899Y724083D01*
X1148399Y723417D01*
G01X1151699Y716350D02*
Y721683D01*
G01Y720217D02*
X1151999Y720883D01*
X1152499Y721417D01*
X1153199Y721683D01*
X1153899Y721417D01*
X1154399Y720883D01*
X1154699Y720217D01*
Y716350D01*
G01Y720217D02*
X1154999Y720883D01*
X1155499Y721417D01*
X1156199Y721683D01*
X1156899Y721417D01*
X1157399Y720883D01*
X1157699Y720083D01*
Y716350D01*
G01X1162699Y721683D02*
Y716350D01*
G01Y723817D02*
X1162499Y723950D01*
Y724217D01*
X1162699Y724350D01*
X1162899Y724217D01*
Y723950D01*
X1162699Y723817D01*
G01X1170699Y716350D02*
Y724350D01*
G01X1188699Y716350D02*
X1184699Y719017D01*
X1188699Y721683D01*
G01X1201199Y717283D02*
X1201699Y716750D01*
X1202399Y716350D01*
X1202999D01*
X1203599Y716617D01*
X1203999Y717017D01*
X1204199Y717550D01*
X1204099Y718350D01*
X1203699Y718750D01*
X1201899Y719550D01*
X1201499Y720483D01*
X1201699Y721150D01*
X1202099Y721550D01*
X1202699Y721683D01*
X1203299Y721550D01*
X1203899Y721150D01*
G01X1210699Y721683D02*
Y716350D01*
G01Y723817D02*
X1210499Y723950D01*
Y724217D01*
X1210699Y724350D01*
X1210899Y724217D01*
Y723950D01*
X1210699Y723817D01*
G01X1217199Y721683D02*
X1220199D01*
X1217199Y716350D01*
X1220199D01*
G01X1225199Y719950D02*
X1228399D01*
X1228099Y720883D01*
X1227599Y721417D01*
X1226899Y721683D01*
X1226199Y721550D01*
X1225599Y721150D01*
X1225199Y720217D01*
X1224999Y719416D01*
Y718617D01*
X1225199Y717817D01*
X1225699Y717017D01*
X1226299Y716483D01*
X1226999Y716350D01*
X1227699Y716617D01*
X1228399Y717416D01*
G01X1244699Y716350D02*
X1240699Y719017D01*
X1244699Y721683D01*
G01X1250699Y716350D02*
Y724350D01*
X1249499Y722750D01*
G01Y716350D02*
X1251899D01*
G01X1256999Y717283D02*
X1257699Y716617D01*
X1258499Y716350D01*
X1259299Y716617D01*
X1259999Y717416D01*
X1260499Y718617D01*
X1260699Y719817D01*
Y721283D01*
X1260499Y722483D01*
X1259999Y723550D01*
X1259399Y724083D01*
X1258699Y724350D01*
X1257899Y724083D01*
X1257299Y723550D01*
X1256899Y722750D01*
X1256699Y721683D01*
X1256899Y720750D01*
X1257399Y719817D01*
X1257999Y719283D01*
X1258699Y719150D01*
X1259499Y719416D01*
X1260099Y720083D01*
X1260699Y721283D01*
G01X1266499Y716350D02*
X1266699Y718083D01*
X1266999Y719550D01*
X1267399Y720883D01*
X1267899Y722350D01*
X1268699Y724350D01*
X1264699D01*
G01X1271699Y716350D02*
Y721683D01*
G01Y720217D02*
X1271999Y720883D01*
X1272499Y721417D01*
X1273199Y721683D01*
X1273899Y721417D01*
X1274399Y720883D01*
X1274699Y720217D01*
Y716350D01*
G01Y720217D02*
X1274999Y720883D01*
X1275499Y721417D01*
X1276199Y721683D01*
X1276899Y721417D01*
X1277399Y720883D01*
X1277699Y720083D01*
Y716350D01*
G01X1282699Y721683D02*
Y716350D01*
G01Y723817D02*
X1282499Y723950D01*
Y724217D01*
X1282699Y724350D01*
X1282899Y724217D01*
Y723950D01*
X1282699Y723817D01*
G01X1290699Y716350D02*
Y724350D01*
G01X1299199Y713683D02*
X1300199Y715017D01*
X1300699Y716350D01*
Y721683D01*
X1300199Y723017D01*
X1299199Y724350D01*
G01X944199Y741350D02*
Y749350D01*
X946599D01*
X947399Y748950D01*
X947999Y748017D01*
X948199Y746950D01*
X947999Y745883D01*
X947499Y745083D01*
X946599Y744683D01*
X944199D01*
G01X954199Y749350D02*
Y741350D01*
G01X951899Y749350D02*
X956499D01*
G01X960099Y741350D02*
Y749350D01*
G01X964299D02*
Y741350D01*
G01Y745350D02*
X960099D01*
G01X976499Y741350D02*
Y749350D01*
G01Y745483D02*
X976999Y746150D01*
X977499Y746550D01*
X978299Y746683D01*
X978899Y746550D01*
X979599Y746017D01*
X979899Y745217D01*
Y741350D01*
G01X986199D02*
X985599Y741483D01*
X984999Y742017D01*
X984599Y742950D01*
X984399Y744017D01*
X984599Y745083D01*
X984999Y746017D01*
X985599Y746550D01*
X986199Y746683D01*
X986799Y746550D01*
X987399Y746017D01*
X987799Y745083D01*
X987899Y744017D01*
X987799Y742950D01*
X987399Y742017D01*
X986799Y741483D01*
X986199Y741350D01*
G01X994199D02*
Y749350D01*
G01X1000699Y744950D02*
X1003899D01*
X1003599Y745883D01*
X1003099Y746417D01*
X1002399Y746683D01*
X1001699Y746550D01*
X1001099Y746150D01*
X1000699Y745217D01*
X1000499Y744416D01*
Y743617D01*
X1000699Y742817D01*
X1001199Y742017D01*
X1001799Y741483D01*
X1002499Y741350D01*
X1003199Y741617D01*
X1003899Y742416D01*
G01X1017599Y741350D02*
Y748150D01*
X1017799Y748817D01*
X1018199Y749217D01*
X1018799Y749350D01*
X1019399Y749083D01*
X1019699Y748417D01*
G01X1018499Y746150D02*
X1016499D01*
G01X1026199Y741350D02*
X1025599Y741483D01*
X1024999Y742017D01*
X1024599Y742950D01*
X1024399Y744017D01*
X1024599Y745083D01*
X1024999Y746017D01*
X1025599Y746550D01*
X1026199Y746683D01*
X1026799Y746550D01*
X1027399Y746017D01*
X1027799Y745083D01*
X1027899Y744017D01*
X1027799Y742950D01*
X1027399Y742017D01*
X1026799Y741483D01*
X1026199Y741350D01*
G01X1032799D02*
Y746683D01*
G01Y745617D02*
X1033299Y746150D01*
X1033799Y746550D01*
X1034499Y746683D01*
X1034999Y746550D01*
X1035599Y746150D01*
G01X1051799Y746017D02*
X1051099Y746550D01*
X1050499Y746683D01*
X1049699Y746417D01*
X1049099Y745883D01*
X1048699Y744950D01*
X1048599Y744017D01*
X1048699Y743083D01*
X1049099Y742283D01*
X1049699Y741617D01*
X1050499Y741350D01*
X1051199Y741617D01*
X1051799Y742150D01*
G01X1058199Y741350D02*
X1057599Y741483D01*
X1056999Y742017D01*
X1056599Y742950D01*
X1056399Y744017D01*
X1056599Y745083D01*
X1056999Y746017D01*
X1057599Y746550D01*
X1058199Y746683D01*
X1058799Y746550D01*
X1059399Y746017D01*
X1059799Y745083D01*
X1059899Y744017D01*
X1059799Y742950D01*
X1059399Y742017D01*
X1058799Y741483D01*
X1058199Y741350D01*
G01X1063199D02*
Y746683D01*
G01Y745217D02*
X1063499Y745883D01*
X1063999Y746417D01*
X1064699Y746683D01*
X1065399Y746417D01*
X1065899Y745883D01*
X1066199Y745217D01*
Y741350D01*
G01Y745217D02*
X1066499Y745883D01*
X1066999Y746417D01*
X1067699Y746683D01*
X1068399Y746417D01*
X1068899Y745883D01*
X1069199Y745083D01*
Y741350D01*
G01X1072399Y738683D02*
Y746683D01*
G01Y745483D02*
X1072899Y746150D01*
X1073399Y746550D01*
X1074199Y746683D01*
X1074899Y746550D01*
X1075599Y745883D01*
X1075899Y744950D01*
X1075999Y744017D01*
X1075899Y743083D01*
X1075599Y742150D01*
X1074999Y741617D01*
X1074199Y741350D01*
X1073499Y741483D01*
X1072799Y741883D01*
X1072399Y742416D01*
G01X1082199Y741350D02*
X1081599Y741483D01*
X1080999Y742017D01*
X1080599Y742950D01*
X1080399Y744017D01*
X1080599Y745083D01*
X1080999Y746017D01*
X1081599Y746550D01*
X1082199Y746683D01*
X1082799Y746550D01*
X1083399Y746017D01*
X1083799Y745083D01*
X1083899Y744017D01*
X1083799Y742950D01*
X1083399Y742017D01*
X1082799Y741483D01*
X1082199Y741350D01*
G01X1088499D02*
Y746683D01*
G01Y745350D02*
X1088899Y746017D01*
X1089499Y746550D01*
X1090299Y746683D01*
X1090999Y746550D01*
X1091599Y746017D01*
X1091899Y745083D01*
Y741350D01*
G01X1096699Y744950D02*
X1099899D01*
X1099599Y745883D01*
X1099099Y746417D01*
X1098399Y746683D01*
X1097699Y746550D01*
X1097099Y746150D01*
X1096699Y745217D01*
X1096499Y744416D01*
Y743617D01*
X1096699Y742817D01*
X1097199Y742017D01*
X1097799Y741483D01*
X1098499Y741350D01*
X1099199Y741617D01*
X1099899Y742416D01*
G01X1104499Y741350D02*
Y746683D01*
G01Y745350D02*
X1104899Y746017D01*
X1105499Y746550D01*
X1106299Y746683D01*
X1106999Y746550D01*
X1107599Y746017D01*
X1107899Y745083D01*
Y741350D01*
G01X1114199Y749350D02*
Y741350D01*
G01X1112799Y746683D02*
X1115599D01*
G01X1129699Y738683D02*
X1128699Y740017D01*
X1128199Y741350D01*
Y746683D01*
X1128699Y748017D01*
X1129699Y749350D01*
G01X1138199Y741350D02*
Y749350D01*
X1136999Y747750D01*
G01Y741350D02*
X1139399D01*
G01X1144299Y744683D02*
X1144999Y745617D01*
X1145599Y746150D01*
X1146399Y746417D01*
X1147099Y746150D01*
X1147599Y745617D01*
X1147999Y744817D01*
X1148099Y743883D01*
X1147999Y743083D01*
X1147599Y742283D01*
X1146999Y741617D01*
X1146299Y741350D01*
X1145499Y741617D01*
X1144799Y742416D01*
X1144399Y743617D01*
X1144299Y744950D01*
X1144499Y746683D01*
X1144799Y747617D01*
X1145299Y748550D01*
X1145999Y749217D01*
X1146699Y749350D01*
X1147399Y749083D01*
X1147899Y748417D01*
G01X1151199Y741350D02*
Y746683D01*
G01Y745217D02*
X1151499Y745883D01*
X1151999Y746417D01*
X1152699Y746683D01*
X1153399Y746417D01*
X1153899Y745883D01*
X1154199Y745217D01*
Y741350D01*
G01Y745217D02*
X1154499Y745883D01*
X1154999Y746417D01*
X1155699Y746683D01*
X1156399Y746417D01*
X1156899Y745883D01*
X1157199Y745083D01*
Y741350D01*
G01X1162199Y746683D02*
Y741350D01*
G01Y748817D02*
X1161999Y748950D01*
Y749217D01*
X1162199Y749350D01*
X1162399Y749217D01*
Y748950D01*
X1162199Y748817D01*
G01X1170199Y741350D02*
Y749350D01*
G01X1188199Y741350D02*
X1184199Y744017D01*
X1188199Y746683D01*
G01X1200699Y742283D02*
X1201199Y741750D01*
X1201899Y741350D01*
X1202499D01*
X1203099Y741617D01*
X1203499Y742017D01*
X1203699Y742550D01*
X1203599Y743350D01*
X1203199Y743750D01*
X1201399Y744550D01*
X1200999Y745483D01*
X1201199Y746150D01*
X1201599Y746550D01*
X1202199Y746683D01*
X1202799Y746550D01*
X1203399Y746150D01*
G01X1210199Y746683D02*
Y741350D01*
G01Y748817D02*
X1209999Y748950D01*
Y749217D01*
X1210199Y749350D01*
X1210399Y749217D01*
Y748950D01*
X1210199Y748817D01*
G01X1216699Y746683D02*
X1219699D01*
X1216699Y741350D01*
X1219699D01*
G01X1224699Y744950D02*
X1227899D01*
X1227599Y745883D01*
X1227099Y746417D01*
X1226399Y746683D01*
X1225699Y746550D01*
X1225099Y746150D01*
X1224699Y745217D01*
X1224499Y744416D01*
Y743617D01*
X1224699Y742817D01*
X1225199Y742017D01*
X1225799Y741483D01*
X1226499Y741350D01*
X1227199Y741617D01*
X1227899Y742416D01*
G01X1244199Y741350D02*
X1240199Y744017D01*
X1244199Y746683D01*
G01X1250199Y741350D02*
Y749350D01*
X1248999Y747750D01*
G01Y741350D02*
X1251399D01*
G01X1256499Y742283D02*
X1257199Y741617D01*
X1257999Y741350D01*
X1258799Y741617D01*
X1259499Y742416D01*
X1259999Y743617D01*
X1260199Y744817D01*
Y746283D01*
X1259999Y747483D01*
X1259499Y748550D01*
X1258899Y749083D01*
X1258199Y749350D01*
X1257399Y749083D01*
X1256799Y748550D01*
X1256399Y747750D01*
X1256199Y746683D01*
X1256399Y745750D01*
X1256899Y744817D01*
X1257499Y744283D01*
X1258199Y744150D01*
X1258999Y744416D01*
X1259599Y745083D01*
X1260199Y746283D01*
G01X1265999Y741350D02*
X1266199Y743083D01*
X1266499Y744550D01*
X1266899Y745883D01*
X1267399Y747350D01*
X1268199Y749350D01*
X1264199D01*
G01X1271199Y741350D02*
Y746683D01*
G01Y745217D02*
X1271499Y745883D01*
X1271999Y746417D01*
X1272699Y746683D01*
X1273399Y746417D01*
X1273899Y745883D01*
X1274199Y745217D01*
Y741350D01*
G01Y745217D02*
X1274499Y745883D01*
X1274999Y746417D01*
X1275699Y746683D01*
X1276399Y746417D01*
X1276899Y745883D01*
X1277199Y745083D01*
Y741350D01*
G01X1282199Y746683D02*
Y741350D01*
G01Y748817D02*
X1281999Y748950D01*
Y749217D01*
X1282199Y749350D01*
X1282399Y749217D01*
Y748950D01*
X1282199Y748817D01*
G01X1290199Y741350D02*
Y749350D01*
G01X1298699Y738683D02*
X1299699Y740017D01*
X1300199Y741350D01*
Y746683D01*
X1299699Y748017D01*
X1298699Y749350D01*
G01X943699Y761850D02*
Y753850D01*
X947699D01*
G01X955499D02*
Y759183D01*
G01Y758250D02*
X955099Y758783D01*
X954499Y759050D01*
X953799Y759183D01*
X953099Y758917D01*
X952499Y758383D01*
X952099Y757583D01*
X951899Y756517D01*
X952099Y755450D01*
X952499Y754650D01*
X953099Y754117D01*
X953799Y753850D01*
X954499Y753983D01*
X955099Y754383D01*
X955499Y754916D01*
G01X960199Y754783D02*
X960699Y754250D01*
X961399Y753850D01*
X961999D01*
X962599Y754117D01*
X962999Y754517D01*
X963199Y755050D01*
X963099Y755850D01*
X962699Y756250D01*
X960899Y757050D01*
X960499Y757983D01*
X960699Y758650D01*
X961099Y759050D01*
X961699Y759183D01*
X962299Y759050D01*
X962899Y758650D01*
G01X968199Y757450D02*
X971399D01*
X971099Y758383D01*
X970599Y758917D01*
X969899Y759183D01*
X969199Y759050D01*
X968599Y758650D01*
X968199Y757717D01*
X967999Y756916D01*
Y756117D01*
X968199Y755317D01*
X968699Y754517D01*
X969299Y753983D01*
X969999Y753850D01*
X970699Y754117D01*
X971399Y754916D01*
G01X976299Y753850D02*
Y759183D01*
G01Y758117D02*
X976799Y758650D01*
X977299Y759050D01*
X977999Y759183D01*
X978499Y759050D01*
X979099Y758650D01*
G01X991899Y759183D02*
X993699Y753850D01*
X995499Y759183D01*
G01X1001699D02*
Y753850D01*
G01Y761317D02*
X1001499Y761450D01*
Y761717D01*
X1001699Y761850D01*
X1001899Y761717D01*
Y761450D01*
X1001699Y761317D01*
G01X1011499Y753850D02*
Y759183D01*
G01Y758250D02*
X1011099Y758783D01*
X1010499Y759050D01*
X1009799Y759183D01*
X1009099Y758917D01*
X1008499Y758383D01*
X1008099Y757583D01*
X1007899Y756517D01*
X1008099Y755450D01*
X1008499Y754650D01*
X1009099Y754117D01*
X1009799Y753850D01*
X1010499Y753983D01*
X1011099Y754383D01*
X1011499Y754916D01*
G01X1023999Y753850D02*
Y761850D01*
G01Y757983D02*
X1024499Y758650D01*
X1024999Y759050D01*
X1025799Y759183D01*
X1026399Y759050D01*
X1027099Y758517D01*
X1027399Y757717D01*
Y753850D01*
G01X1033699D02*
X1033099Y753983D01*
X1032499Y754517D01*
X1032099Y755450D01*
X1031899Y756517D01*
X1032099Y757583D01*
X1032499Y758517D01*
X1033099Y759050D01*
X1033699Y759183D01*
X1034299Y759050D01*
X1034899Y758517D01*
X1035299Y757583D01*
X1035399Y756517D01*
X1035299Y755450D01*
X1034899Y754517D01*
X1034299Y753983D01*
X1033699Y753850D01*
G01X1041699D02*
Y761850D01*
G01X1048199Y757450D02*
X1051399D01*
X1051099Y758383D01*
X1050599Y758917D01*
X1049899Y759183D01*
X1049199Y759050D01*
X1048599Y758650D01*
X1048199Y757717D01*
X1047999Y756916D01*
Y756117D01*
X1048199Y755317D01*
X1048699Y754517D01*
X1049299Y753983D01*
X1049999Y753850D01*
X1050699Y754117D01*
X1051399Y754916D01*
G01X1065199Y751183D02*
X1064199Y752517D01*
X1063699Y753850D01*
Y759183D01*
X1064199Y760517D01*
X1065199Y761850D01*
G01X1071899Y753850D02*
Y761850D01*
G01Y757850D02*
X1072399Y758650D01*
X1072999Y759050D01*
X1073599Y759183D01*
X1074499Y758917D01*
X1075099Y758383D01*
X1075499Y757450D01*
Y756383D01*
X1075299Y755317D01*
X1074899Y754517D01*
X1074199Y753983D01*
X1073599Y753850D01*
X1072999Y753983D01*
X1072399Y754383D01*
X1071899Y755050D01*
G01X1080199Y757450D02*
X1083399D01*
X1083099Y758383D01*
X1082599Y758917D01*
X1081899Y759183D01*
X1081199Y759050D01*
X1080599Y758650D01*
X1080199Y757717D01*
X1079999Y756916D01*
Y756117D01*
X1080199Y755317D01*
X1080699Y754517D01*
X1081299Y753983D01*
X1081999Y753850D01*
X1082699Y754117D01*
X1083399Y754916D01*
G01X1089099Y753850D02*
Y760650D01*
X1089299Y761317D01*
X1089699Y761717D01*
X1090299Y761850D01*
X1090899Y761583D01*
X1091199Y760917D01*
G01X1089999Y758650D02*
X1087999D01*
G01X1097699Y753850D02*
X1097099Y753983D01*
X1096499Y754517D01*
X1096099Y755450D01*
X1095899Y756517D01*
X1096099Y757583D01*
X1096499Y758517D01*
X1097099Y759050D01*
X1097699Y759183D01*
X1098299Y759050D01*
X1098899Y758517D01*
X1099299Y757583D01*
X1099399Y756517D01*
X1099299Y755450D01*
X1098899Y754517D01*
X1098299Y753983D01*
X1097699Y753850D01*
G01X1104299D02*
Y759183D01*
G01Y758117D02*
X1104799Y758650D01*
X1105299Y759050D01*
X1105999Y759183D01*
X1106499Y759050D01*
X1107099Y758650D01*
G01X1112199Y757450D02*
X1115399D01*
X1115099Y758383D01*
X1114599Y758917D01*
X1113899Y759183D01*
X1113199Y759050D01*
X1112599Y758650D01*
X1112199Y757717D01*
X1111999Y756916D01*
Y756117D01*
X1112199Y755317D01*
X1112699Y754517D01*
X1113299Y753983D01*
X1113999Y753850D01*
X1114699Y754117D01*
X1115399Y754916D01*
G01X1129699Y761850D02*
Y753850D01*
G01X1128299Y759183D02*
X1131099D01*
G01X1135999Y753850D02*
Y761850D01*
G01Y757983D02*
X1136499Y758650D01*
X1136999Y759050D01*
X1137799Y759183D01*
X1138399Y759050D01*
X1139099Y758517D01*
X1139399Y757717D01*
Y753850D01*
G01X1144199Y757450D02*
X1147399D01*
X1147099Y758383D01*
X1146599Y758917D01*
X1145899Y759183D01*
X1145199Y759050D01*
X1144599Y758650D01*
X1144199Y757717D01*
X1143999Y756916D01*
Y756117D01*
X1144199Y755317D01*
X1144699Y754517D01*
X1145299Y753983D01*
X1145999Y753850D01*
X1146699Y754117D01*
X1147399Y754916D01*
G01X1163299Y758517D02*
X1162599Y759050D01*
X1161999Y759183D01*
X1161199Y758917D01*
X1160599Y758383D01*
X1160199Y757450D01*
X1160099Y756517D01*
X1160199Y755583D01*
X1160599Y754783D01*
X1161199Y754117D01*
X1161999Y753850D01*
X1162699Y754117D01*
X1163299Y754650D01*
G01X1169699Y753850D02*
X1169099Y753983D01*
X1168499Y754517D01*
X1168099Y755450D01*
X1167899Y756517D01*
X1168099Y757583D01*
X1168499Y758517D01*
X1169099Y759050D01*
X1169699Y759183D01*
X1170299Y759050D01*
X1170899Y758517D01*
X1171299Y757583D01*
X1171399Y756517D01*
X1171299Y755450D01*
X1170899Y754517D01*
X1170299Y753983D01*
X1169699Y753850D01*
G01X1175899Y751183D02*
Y759183D01*
G01Y757983D02*
X1176399Y758650D01*
X1176899Y759050D01*
X1177699Y759183D01*
X1178399Y759050D01*
X1179099Y758383D01*
X1179399Y757450D01*
X1179499Y756517D01*
X1179399Y755583D01*
X1179099Y754650D01*
X1178499Y754117D01*
X1177699Y753850D01*
X1176999Y753983D01*
X1176299Y754383D01*
X1175899Y754916D01*
G01X1183899Y751183D02*
Y759183D01*
G01Y757983D02*
X1184399Y758650D01*
X1184899Y759050D01*
X1185699Y759183D01*
X1186399Y759050D01*
X1187099Y758383D01*
X1187399Y757450D01*
X1187499Y756517D01*
X1187399Y755583D01*
X1187099Y754650D01*
X1186499Y754117D01*
X1185699Y753850D01*
X1184999Y753983D01*
X1184299Y754383D01*
X1183899Y754916D01*
G01X1192199Y757450D02*
X1195399D01*
X1195099Y758383D01*
X1194599Y758917D01*
X1193899Y759183D01*
X1193199Y759050D01*
X1192599Y758650D01*
X1192199Y757717D01*
X1191999Y756916D01*
Y756117D01*
X1192199Y755317D01*
X1192699Y754517D01*
X1193299Y753983D01*
X1193999Y753850D01*
X1194699Y754117D01*
X1195399Y754916D01*
G01X1200299Y753850D02*
Y759183D01*
G01Y758117D02*
X1200799Y758650D01*
X1201299Y759050D01*
X1201999Y759183D01*
X1202499Y759050D01*
X1203099Y758650D01*
G01X1215899Y751183D02*
Y759183D01*
G01Y757983D02*
X1216399Y758650D01*
X1216899Y759050D01*
X1217699Y759183D01*
X1218399Y759050D01*
X1219099Y758383D01*
X1219399Y757450D01*
X1219499Y756517D01*
X1219399Y755583D01*
X1219099Y754650D01*
X1218499Y754117D01*
X1217699Y753850D01*
X1216999Y753983D01*
X1216299Y754383D01*
X1215899Y754916D01*
G01X1225699Y753850D02*
Y761850D01*
G01X1235499Y753850D02*
Y759183D01*
G01Y758250D02*
X1235099Y758783D01*
X1234499Y759050D01*
X1233799Y759183D01*
X1233099Y758917D01*
X1232499Y758383D01*
X1232099Y757583D01*
X1231899Y756517D01*
X1232099Y755450D01*
X1232499Y754650D01*
X1233099Y754117D01*
X1233799Y753850D01*
X1234499Y753983D01*
X1235099Y754383D01*
X1235499Y754916D01*
G01X1241699Y761850D02*
Y753850D01*
G01X1240299Y759183D02*
X1243099D01*
G01X1249699D02*
Y753850D01*
G01Y761317D02*
X1249499Y761450D01*
Y761717D01*
X1249699Y761850D01*
X1249899Y761717D01*
Y761450D01*
X1249699Y761317D01*
G01X1255999Y753850D02*
Y759183D01*
G01Y757850D02*
X1256399Y758517D01*
X1256999Y759050D01*
X1257799Y759183D01*
X1258499Y759050D01*
X1259099Y758517D01*
X1259399Y757583D01*
Y753850D01*
G01X1264299Y751850D02*
X1264999Y751317D01*
X1265799Y751183D01*
X1266499Y751317D01*
X1267099Y751983D01*
X1267499Y752917D01*
Y759183D01*
G01Y758117D02*
X1267099Y758650D01*
X1266499Y759050D01*
X1265799Y759183D01*
X1264999Y758917D01*
X1264499Y758383D01*
X1264099Y757450D01*
X1263899Y756517D01*
X1263999Y755717D01*
X1264399Y754783D01*
X1264999Y754117D01*
X1265799Y753850D01*
X1266399Y753983D01*
X1267099Y754517D01*
X1267499Y755050D01*
G01X1274199Y751183D02*
X1275199Y752517D01*
X1275699Y753850D01*
Y759183D01*
X1275199Y760517D01*
X1274199Y761850D01*
G01X943199Y774350D02*
X945699Y766350D01*
X948199Y774350D01*
G01X953699Y771683D02*
Y766350D01*
G01Y773817D02*
X953499Y773950D01*
Y774217D01*
X953699Y774350D01*
X953899Y774217D01*
Y773950D01*
X953699Y773817D01*
G01X963499Y766350D02*
Y771683D01*
G01Y770750D02*
X963099Y771283D01*
X962499Y771550D01*
X961799Y771683D01*
X961099Y771417D01*
X960499Y770883D01*
X960099Y770083D01*
X959899Y769017D01*
X960099Y767950D01*
X960499Y767150D01*
X961099Y766617D01*
X961799Y766350D01*
X962499Y766483D01*
X963099Y766883D01*
X963499Y767416D01*
G01X975599Y766350D02*
Y774350D01*
G01X979799D02*
Y766350D01*
G01Y770350D02*
X975599D01*
G01X985699Y766350D02*
X985099Y766483D01*
X984499Y767017D01*
X984099Y767950D01*
X983899Y769017D01*
X984099Y770083D01*
X984499Y771017D01*
X985099Y771550D01*
X985699Y771683D01*
X986299Y771550D01*
X986899Y771017D01*
X987299Y770083D01*
X987399Y769017D01*
X987299Y767950D01*
X986899Y767017D01*
X986299Y766483D01*
X985699Y766350D01*
G01X993699D02*
Y774350D01*
G01X1000199Y769950D02*
X1003399D01*
X1003099Y770883D01*
X1002599Y771417D01*
X1001899Y771683D01*
X1001199Y771550D01*
X1000599Y771150D01*
X1000199Y770217D01*
X999999Y769416D01*
Y768617D01*
X1000199Y767817D01*
X1000699Y767017D01*
X1001299Y766483D01*
X1001999Y766350D01*
X1002699Y766617D01*
X1003399Y767416D01*
G01X1017199Y763683D02*
X1016199Y765017D01*
X1015699Y766350D01*
Y771683D01*
X1016199Y773017D01*
X1017199Y774350D01*
G01X1023999Y766350D02*
Y774350D01*
G01Y770483D02*
X1024499Y771150D01*
X1024999Y771550D01*
X1025799Y771683D01*
X1026399Y771550D01*
X1027099Y771017D01*
X1027399Y770217D01*
Y766350D01*
G01X1033699D02*
X1033099Y766483D01*
X1032499Y767017D01*
X1032099Y767950D01*
X1031899Y769017D01*
X1032099Y770083D01*
X1032499Y771017D01*
X1033099Y771550D01*
X1033699Y771683D01*
X1034299Y771550D01*
X1034899Y771017D01*
X1035299Y770083D01*
X1035399Y769017D01*
X1035299Y767950D01*
X1034899Y767017D01*
X1034299Y766483D01*
X1033699Y766350D01*
G01X1041699D02*
Y774350D01*
G01X1048199Y769950D02*
X1051399D01*
X1051099Y770883D01*
X1050599Y771417D01*
X1049899Y771683D01*
X1049199Y771550D01*
X1048599Y771150D01*
X1048199Y770217D01*
X1047999Y769416D01*
Y768617D01*
X1048199Y767817D01*
X1048699Y767017D01*
X1049299Y766483D01*
X1049999Y766350D01*
X1050699Y766617D01*
X1051399Y767416D01*
G01X1064199Y767283D02*
X1064699Y766750D01*
X1065399Y766350D01*
X1065999D01*
X1066599Y766617D01*
X1066999Y767017D01*
X1067199Y767550D01*
X1067099Y768350D01*
X1066699Y768750D01*
X1064899Y769550D01*
X1064499Y770483D01*
X1064699Y771150D01*
X1065099Y771550D01*
X1065699Y771683D01*
X1066299Y771550D01*
X1066899Y771150D01*
G01X1073699Y771683D02*
Y766350D01*
G01Y773817D02*
X1073499Y773950D01*
Y774217D01*
X1073699Y774350D01*
X1073899Y774217D01*
Y773950D01*
X1073699Y773817D01*
G01X1080199Y771683D02*
X1083199D01*
X1080199Y766350D01*
X1083199D01*
G01X1088199Y769950D02*
X1091399D01*
X1091099Y770883D01*
X1090599Y771417D01*
X1089899Y771683D01*
X1089199Y771550D01*
X1088599Y771150D01*
X1088199Y770217D01*
X1087999Y769416D01*
Y768617D01*
X1088199Y767817D01*
X1088699Y767017D01*
X1089299Y766483D01*
X1089999Y766350D01*
X1090699Y766617D01*
X1091399Y767416D01*
G01X1107699Y766350D02*
X1103699Y769017D01*
X1107699Y771683D01*
G01X1112399Y767817D02*
X1114999D01*
G01Y770217D02*
X1112399D01*
G01X1121699Y766350D02*
Y774350D01*
X1120499Y772750D01*
G01Y766350D02*
X1122899D01*
G01X1127799Y769683D02*
X1128499Y770617D01*
X1129099Y771150D01*
X1129899Y771417D01*
X1130599Y771150D01*
X1131099Y770617D01*
X1131499Y769817D01*
X1131599Y768883D01*
X1131499Y768083D01*
X1131099Y767283D01*
X1130499Y766617D01*
X1129799Y766350D01*
X1128999Y766617D01*
X1128299Y767416D01*
X1127899Y768617D01*
X1127799Y769950D01*
X1127999Y771683D01*
X1128299Y772617D01*
X1128799Y773550D01*
X1129499Y774217D01*
X1130199Y774350D01*
X1130899Y774083D01*
X1131399Y773417D01*
G01X1142699Y766350D02*
Y771683D01*
G01Y770217D02*
X1142999Y770883D01*
X1143499Y771417D01*
X1144199Y771683D01*
X1144899Y771417D01*
X1145399Y770883D01*
X1145699Y770217D01*
Y766350D01*
G01Y770217D02*
X1145999Y770883D01*
X1146499Y771417D01*
X1147199Y771683D01*
X1147899Y771417D01*
X1148399Y770883D01*
X1148699Y770083D01*
Y766350D01*
G01X1153699Y771683D02*
Y766350D01*
G01Y773817D02*
X1153499Y773950D01*
Y774217D01*
X1153699Y774350D01*
X1153899Y774217D01*
Y773950D01*
X1153699Y773817D01*
G01X1161699Y766350D02*
Y774350D01*
G01X1170199Y763683D02*
X1171199Y765017D01*
X1171699Y766350D01*
Y771683D01*
X1171199Y773017D01*
X1170199Y774350D01*
G01X958199Y786850D02*
Y778850D01*
G01X956799Y784183D02*
X959599D01*
G01X964499Y778850D02*
Y786850D01*
G01Y782983D02*
X964999Y783650D01*
X965499Y784050D01*
X966299Y784183D01*
X966899Y784050D01*
X967599Y783517D01*
X967899Y782717D01*
Y778850D01*
G01X972699Y782450D02*
X975899D01*
X975599Y783383D01*
X975099Y783917D01*
X974399Y784183D01*
X973699Y784050D01*
X973099Y783650D01*
X972699Y782717D01*
X972499Y781916D01*
Y781117D01*
X972699Y780317D01*
X973199Y779517D01*
X973799Y778983D01*
X974499Y778850D01*
X975199Y779117D01*
X975899Y779916D01*
G01X988799Y778850D02*
Y784183D01*
G01Y783117D02*
X989299Y783650D01*
X989799Y784050D01*
X990499Y784183D01*
X990999Y784050D01*
X991599Y783650D01*
G01X996699Y782450D02*
X999899D01*
X999599Y783383D01*
X999099Y783917D01*
X998399Y784183D01*
X997699Y784050D01*
X997099Y783650D01*
X996699Y782717D01*
X996499Y781916D01*
Y781117D01*
X996699Y780317D01*
X997199Y779517D01*
X997799Y778983D01*
X998499Y778850D01*
X999199Y779117D01*
X999899Y779916D01*
G01X1006199Y778850D02*
Y786850D01*
G01X1015999Y778850D02*
Y784183D01*
G01Y783250D02*
X1015599Y783783D01*
X1014999Y784050D01*
X1014299Y784183D01*
X1013599Y783917D01*
X1012999Y783383D01*
X1012599Y782583D01*
X1012399Y781517D01*
X1012599Y780450D01*
X1012999Y779650D01*
X1013599Y779117D01*
X1014299Y778850D01*
X1014999Y778983D01*
X1015599Y779383D01*
X1015999Y779916D01*
G01X1022199Y786850D02*
Y778850D01*
G01X1020799Y784183D02*
X1023599D01*
G01X1030199D02*
Y778850D01*
G01Y786317D02*
X1029999Y786450D01*
Y786717D01*
X1030199Y786850D01*
X1030399Y786717D01*
Y786450D01*
X1030199Y786317D01*
G01X1036399Y784183D02*
X1038199Y778850D01*
X1039999Y784183D01*
G01X1044699Y782450D02*
X1047899D01*
X1047599Y783383D01*
X1047099Y783917D01*
X1046399Y784183D01*
X1045699Y784050D01*
X1045099Y783650D01*
X1044699Y782717D01*
X1044499Y781916D01*
Y781117D01*
X1044699Y780317D01*
X1045199Y779517D01*
X1045799Y778983D01*
X1046499Y778850D01*
X1047199Y779117D01*
X1047899Y779916D01*
G01X1062199Y778850D02*
Y786850D01*
G01X1070199Y778850D02*
X1069599Y778983D01*
X1068999Y779517D01*
X1068599Y780450D01*
X1068399Y781517D01*
X1068599Y782583D01*
X1068999Y783517D01*
X1069599Y784050D01*
X1070199Y784183D01*
X1070799Y784050D01*
X1071399Y783517D01*
X1071799Y782583D01*
X1071899Y781517D01*
X1071799Y780450D01*
X1071399Y779517D01*
X1070799Y778983D01*
X1070199Y778850D01*
G01X1079799Y783517D02*
X1079099Y784050D01*
X1078499Y784183D01*
X1077699Y783917D01*
X1077099Y783383D01*
X1076699Y782450D01*
X1076599Y781517D01*
X1076699Y780583D01*
X1077099Y779783D01*
X1077699Y779117D01*
X1078499Y778850D01*
X1079199Y779117D01*
X1079799Y779650D01*
G01X1087999Y778850D02*
Y784183D01*
G01Y783250D02*
X1087599Y783783D01*
X1086999Y784050D01*
X1086299Y784183D01*
X1085599Y783917D01*
X1084999Y783383D01*
X1084599Y782583D01*
X1084399Y781517D01*
X1084599Y780450D01*
X1084999Y779650D01*
X1085599Y779117D01*
X1086299Y778850D01*
X1086999Y778983D01*
X1087599Y779383D01*
X1087999Y779916D01*
G01X1094199Y786850D02*
Y778850D01*
G01X1092799Y784183D02*
X1095599D01*
G01X1102199D02*
Y778850D01*
G01Y786317D02*
X1101999Y786450D01*
Y786717D01*
X1102199Y786850D01*
X1102399Y786717D01*
Y786450D01*
X1102199Y786317D01*
G01X1110199Y778850D02*
X1109599Y778983D01*
X1108999Y779517D01*
X1108599Y780450D01*
X1108399Y781517D01*
X1108599Y782583D01*
X1108999Y783517D01*
X1109599Y784050D01*
X1110199Y784183D01*
X1110799Y784050D01*
X1111399Y783517D01*
X1111799Y782583D01*
X1111899Y781517D01*
X1111799Y780450D01*
X1111399Y779517D01*
X1110799Y778983D01*
X1110199Y778850D01*
G01X1116499D02*
Y784183D01*
G01Y782850D02*
X1116899Y783517D01*
X1117499Y784050D01*
X1118299Y784183D01*
X1118999Y784050D01*
X1119599Y783517D01*
X1119899Y782583D01*
Y778850D01*
G01X1134199D02*
X1133599Y778983D01*
X1132999Y779517D01*
X1132599Y780450D01*
X1132399Y781517D01*
X1132599Y782583D01*
X1132999Y783517D01*
X1133599Y784050D01*
X1134199Y784183D01*
X1134799Y784050D01*
X1135399Y783517D01*
X1135799Y782583D01*
X1135899Y781517D01*
X1135799Y780450D01*
X1135399Y779517D01*
X1134799Y778983D01*
X1134199Y778850D01*
G01X1141599D02*
Y785650D01*
X1141799Y786317D01*
X1142199Y786717D01*
X1142799Y786850D01*
X1143399Y786583D01*
X1143699Y785917D01*
G01X1142499Y783650D02*
X1140499D01*
G01X1156499Y778850D02*
Y786850D01*
G01Y782983D02*
X1156999Y783650D01*
X1157499Y784050D01*
X1158299Y784183D01*
X1158899Y784050D01*
X1159599Y783517D01*
X1159899Y782717D01*
Y778850D01*
G01X1166199D02*
X1165599Y778983D01*
X1164999Y779517D01*
X1164599Y780450D01*
X1164399Y781517D01*
X1164599Y782583D01*
X1164999Y783517D01*
X1165599Y784050D01*
X1166199Y784183D01*
X1166799Y784050D01*
X1167399Y783517D01*
X1167799Y782583D01*
X1167899Y781517D01*
X1167799Y780450D01*
X1167399Y779517D01*
X1166799Y778983D01*
X1166199Y778850D01*
G01X1174199D02*
Y786850D01*
G01X1180699Y782450D02*
X1183899D01*
X1183599Y783383D01*
X1183099Y783917D01*
X1182399Y784183D01*
X1181699Y784050D01*
X1181099Y783650D01*
X1180699Y782717D01*
X1180499Y781916D01*
Y781117D01*
X1180699Y780317D01*
X1181199Y779517D01*
X1181799Y778983D01*
X1182499Y778850D01*
X1183199Y779117D01*
X1183899Y779916D01*
G01X1198199Y786850D02*
Y778850D01*
G01X1196799Y784183D02*
X1199599D01*
G01X1206199Y778850D02*
X1205599Y778983D01*
X1204999Y779517D01*
X1204599Y780450D01*
X1204399Y781517D01*
X1204599Y782583D01*
X1204999Y783517D01*
X1205599Y784050D01*
X1206199Y784183D01*
X1206799Y784050D01*
X1207399Y783517D01*
X1207799Y782583D01*
X1207899Y781517D01*
X1207799Y780450D01*
X1207399Y779517D01*
X1206799Y778983D01*
X1206199Y778850D01*
G01X1220499D02*
Y786850D01*
G01Y782983D02*
X1220999Y783650D01*
X1221499Y784050D01*
X1222299Y784183D01*
X1222899Y784050D01*
X1223599Y783517D01*
X1223899Y782717D01*
Y778850D01*
G01X1230199D02*
X1229599Y778983D01*
X1228999Y779517D01*
X1228599Y780450D01*
X1228399Y781517D01*
X1228599Y782583D01*
X1228999Y783517D01*
X1229599Y784050D01*
X1230199Y784183D01*
X1230799Y784050D01*
X1231399Y783517D01*
X1231799Y782583D01*
X1231899Y781517D01*
X1231799Y780450D01*
X1231399Y779517D01*
X1230799Y778983D01*
X1230199Y778850D01*
G01X1238199D02*
Y786850D01*
G01X1244699Y782450D02*
X1247899D01*
X1247599Y783383D01*
X1247099Y783917D01*
X1246399Y784183D01*
X1245699Y784050D01*
X1245099Y783650D01*
X1244699Y782717D01*
X1244499Y781916D01*
Y781117D01*
X1244699Y780317D01*
X1245199Y779517D01*
X1245799Y778983D01*
X1246499Y778850D01*
X1247199Y779117D01*
X1247899Y779916D01*
G01X1104499Y801350D02*
X1106899D01*
G01X1105699D02*
Y793350D01*
G01X1104499D02*
X1106899D01*
G01X1113699Y801350D02*
Y793350D01*
G01X1112299Y798683D02*
X1115099D01*
G01X1120199Y796950D02*
X1123399D01*
X1123099Y797883D01*
X1122599Y798417D01*
X1121899Y798683D01*
X1121199Y798550D01*
X1120599Y798150D01*
X1120199Y797217D01*
X1119999Y796416D01*
Y795617D01*
X1120199Y794817D01*
X1120699Y794017D01*
X1121299Y793483D01*
X1121999Y793350D01*
X1122699Y793617D01*
X1123399Y794416D01*
G01X1126699Y793350D02*
Y798683D01*
G01Y797217D02*
X1126999Y797883D01*
X1127499Y798417D01*
X1128199Y798683D01*
X1128899Y798417D01*
X1129399Y797883D01*
X1129699Y797217D01*
Y793350D01*
G01Y797217D02*
X1129999Y797883D01*
X1130499Y798417D01*
X1131199Y798683D01*
X1131899Y798417D01*
X1132399Y797883D01*
X1132699Y797083D01*
Y793350D01*
G01X1136199Y794283D02*
X1136699Y793750D01*
X1137399Y793350D01*
X1137999D01*
X1138599Y793617D01*
X1138999Y794017D01*
X1139199Y794550D01*
X1139099Y795350D01*
X1138699Y795750D01*
X1136899Y796550D01*
X1136499Y797483D01*
X1136699Y798150D01*
X1137099Y798550D01*
X1137699Y798683D01*
X1138299Y798550D01*
X1138899Y798150D01*
G01X1358699Y628950D02*
Y636950D01*
X1357499Y635350D01*
G01Y628950D02*
X1359899D01*
G01X1366699Y628683D02*
X1366499Y628817D01*
Y629083D01*
X1366699Y629217D01*
X1366899Y629083D01*
Y628817D01*
X1366699Y628683D01*
G01X1374699Y636950D02*
X1373899Y636683D01*
X1373299Y636017D01*
X1372899Y635217D01*
X1372599Y634150D01*
X1372499Y632950D01*
X1372599Y631750D01*
X1372899Y630683D01*
X1373299Y629883D01*
X1373899Y629217D01*
X1374699Y628950D01*
X1375499Y629217D01*
X1376099Y629883D01*
X1376499Y630683D01*
X1376799Y631750D01*
X1376899Y632950D01*
X1376799Y634150D01*
X1376499Y635217D01*
X1376099Y636017D01*
X1375499Y636683D01*
X1374699Y636950D01*
G01X1379699Y628950D02*
Y634283D01*
G01Y632817D02*
X1379999Y633483D01*
X1380499Y634017D01*
X1381199Y634283D01*
X1381899Y634017D01*
X1382399Y633483D01*
X1382699Y632817D01*
Y628950D01*
G01Y632817D02*
X1382999Y633483D01*
X1383499Y634017D01*
X1384199Y634283D01*
X1384899Y634017D01*
X1385399Y633483D01*
X1385699Y632683D01*
Y628950D01*
G01X1390699Y634283D02*
Y628950D01*
G01Y636417D02*
X1390499Y636550D01*
Y636817D01*
X1390699Y636950D01*
X1390899Y636817D01*
Y636550D01*
X1390699Y636417D01*
G01X1398699Y628950D02*
Y636950D01*
G01X1411699Y628950D02*
Y634283D01*
G01Y632817D02*
X1411999Y633483D01*
X1412499Y634017D01*
X1413199Y634283D01*
X1413899Y634017D01*
X1414399Y633483D01*
X1414699Y632817D01*
Y628950D01*
G01Y632817D02*
X1414999Y633483D01*
X1415499Y634017D01*
X1416199Y634283D01*
X1416899Y634017D01*
X1417399Y633483D01*
X1417699Y632683D01*
Y628950D01*
G01X1424499D02*
Y634283D01*
G01Y633350D02*
X1424099Y633883D01*
X1423499Y634150D01*
X1422799Y634283D01*
X1422099Y634017D01*
X1421499Y633483D01*
X1421099Y632683D01*
X1420899Y631617D01*
X1421099Y630550D01*
X1421499Y629750D01*
X1422099Y629217D01*
X1422799Y628950D01*
X1423499Y629083D01*
X1424099Y629483D01*
X1424499Y630016D01*
G01X1429199Y634283D02*
X1432199Y628950D01*
G01Y634283D02*
X1429199Y628950D01*
G01X1369599Y643517D02*
X1371999D01*
G01X1370699Y645250D02*
Y641783D01*
G01X1376899Y640583D02*
X1380499Y648850D01*
G01X1385399Y643517D02*
X1387999D01*
G01X1392499Y642050D02*
X1393099Y641383D01*
X1393799Y640983D01*
X1394699Y640850D01*
X1395599Y641117D01*
X1396299Y641650D01*
X1396799Y642583D01*
X1396899Y643650D01*
X1396699Y644717D01*
X1396199Y645383D01*
X1395499Y645917D01*
X1394799Y646050D01*
X1394099Y645917D01*
X1393199Y645383D01*
X1393499Y648850D01*
X1396199D01*
G01X1399699Y640850D02*
Y646183D01*
G01Y644717D02*
X1399999Y645383D01*
X1400499Y645917D01*
X1401199Y646183D01*
X1401899Y645917D01*
X1402399Y645383D01*
X1402699Y644717D01*
Y640850D01*
G01Y644717D02*
X1402999Y645383D01*
X1403499Y645917D01*
X1404199Y646183D01*
X1404899Y645917D01*
X1405399Y645383D01*
X1405699Y644583D01*
Y640850D01*
G01X1410699Y646183D02*
Y640850D01*
G01Y648317D02*
X1410499Y648450D01*
Y648717D01*
X1410699Y648850D01*
X1410899Y648717D01*
Y648450D01*
X1410699Y648317D01*
G01X1418699Y640850D02*
Y648850D01*
G01X1369599Y656517D02*
X1371999D01*
G01X1370699Y658250D02*
Y654783D01*
G01X1376899Y653583D02*
X1380499Y661850D01*
G01X1385399Y656517D02*
X1387999D01*
G01X1392499Y655050D02*
X1393099Y654383D01*
X1393799Y653983D01*
X1394699Y653850D01*
X1395599Y654117D01*
X1396299Y654650D01*
X1396799Y655583D01*
X1396899Y656650D01*
X1396699Y657717D01*
X1396199Y658383D01*
X1395499Y658917D01*
X1394799Y659050D01*
X1394099Y658917D01*
X1393199Y658383D01*
X1393499Y661850D01*
X1396199D01*
G01X1399699Y653850D02*
Y659183D01*
G01Y657717D02*
X1399999Y658383D01*
X1400499Y658917D01*
X1401199Y659183D01*
X1401899Y658917D01*
X1402399Y658383D01*
X1402699Y657717D01*
Y653850D01*
G01Y657717D02*
X1402999Y658383D01*
X1403499Y658917D01*
X1404199Y659183D01*
X1404899Y658917D01*
X1405399Y658383D01*
X1405699Y657583D01*
Y653850D01*
G01X1410699Y659183D02*
Y653850D01*
G01Y661317D02*
X1410499Y661450D01*
Y661717D01*
X1410699Y661850D01*
X1410899Y661717D01*
Y661450D01*
X1410699Y661317D01*
G01X1418699Y653850D02*
Y661850D01*
G01X1369599Y669017D02*
X1371999D01*
G01X1370699Y670750D02*
Y667283D01*
G01X1376899Y666083D02*
X1380499Y674350D01*
G01X1385399Y669017D02*
X1387999D01*
G01X1394699Y674350D02*
X1393899Y674083D01*
X1393299Y673417D01*
X1392899Y672617D01*
X1392599Y671550D01*
X1392499Y670350D01*
X1392599Y669150D01*
X1392899Y668083D01*
X1393299Y667283D01*
X1393899Y666617D01*
X1394699Y666350D01*
X1395499Y666617D01*
X1396099Y667283D01*
X1396499Y668083D01*
X1396799Y669150D01*
X1396899Y670350D01*
X1396799Y671550D01*
X1396499Y672617D01*
X1396099Y673417D01*
X1395499Y674083D01*
X1394699Y674350D01*
G01X1402699Y666083D02*
X1402499Y666217D01*
Y666483D01*
X1402699Y666617D01*
X1402899Y666483D01*
Y666217D01*
X1402699Y666083D01*
G01X1410699Y674350D02*
X1409899Y674083D01*
X1409299Y673417D01*
X1408899Y672617D01*
X1408599Y671550D01*
X1408499Y670350D01*
X1408599Y669150D01*
X1408899Y668083D01*
X1409299Y667283D01*
X1409899Y666617D01*
X1410699Y666350D01*
X1411499Y666617D01*
X1412099Y667283D01*
X1412499Y668083D01*
X1412799Y669150D01*
X1412899Y670350D01*
X1412799Y671550D01*
X1412499Y672617D01*
X1412099Y673417D01*
X1411499Y674083D01*
X1410699Y674350D01*
G01X1416499Y667550D02*
X1417099Y666883D01*
X1417799Y666483D01*
X1418699Y666350D01*
X1419599Y666617D01*
X1420299Y667150D01*
X1420799Y668083D01*
X1420899Y669150D01*
X1420699Y670217D01*
X1420199Y670883D01*
X1419499Y671417D01*
X1418799Y671550D01*
X1418099Y671417D01*
X1417199Y670883D01*
X1417499Y674350D01*
X1420199D01*
G01X1423699Y666350D02*
Y671683D01*
G01Y670217D02*
X1423999Y670883D01*
X1424499Y671417D01*
X1425199Y671683D01*
X1425899Y671417D01*
X1426399Y670883D01*
X1426699Y670217D01*
Y666350D01*
G01Y670217D02*
X1426999Y670883D01*
X1427499Y671417D01*
X1428199Y671683D01*
X1428899Y671417D01*
X1429399Y670883D01*
X1429699Y670083D01*
Y666350D01*
G01X1431699D02*
Y671683D01*
G01Y670217D02*
X1431999Y670883D01*
X1432499Y671417D01*
X1433199Y671683D01*
X1433899Y671417D01*
X1434399Y670883D01*
X1434699Y670217D01*
Y666350D01*
G01Y670217D02*
X1434999Y670883D01*
X1435499Y671417D01*
X1436199Y671683D01*
X1436899Y671417D01*
X1437399Y670883D01*
X1437699Y670083D01*
Y666350D01*
G01X1353099Y681217D02*
X1355499D01*
G01X1354199Y682950D02*
Y679483D01*
G01X1362199Y686550D02*
X1361399Y686283D01*
X1360799Y685617D01*
X1360399Y684817D01*
X1360099Y683750D01*
X1359999Y682550D01*
X1360099Y681350D01*
X1360399Y680283D01*
X1360799Y679483D01*
X1361399Y678817D01*
X1362199Y678550D01*
X1362999Y678817D01*
X1363599Y679483D01*
X1363999Y680283D01*
X1364299Y681350D01*
X1364399Y682550D01*
X1364299Y683750D01*
X1363999Y684817D01*
X1363599Y685617D01*
X1362999Y686283D01*
X1362199Y686550D01*
G01X1370199Y678283D02*
X1369999Y678417D01*
Y678683D01*
X1370199Y678817D01*
X1370399Y678683D01*
Y678417D01*
X1370199Y678283D01*
G01X1378199Y686550D02*
X1377399Y686283D01*
X1376799Y685617D01*
X1376399Y684817D01*
X1376099Y683750D01*
X1375999Y682550D01*
X1376099Y681350D01*
X1376399Y680283D01*
X1376799Y679483D01*
X1377399Y678817D01*
X1378199Y678550D01*
X1378999Y678817D01*
X1379599Y679483D01*
X1379999Y680283D01*
X1380299Y681350D01*
X1380399Y682550D01*
X1380299Y683750D01*
X1379999Y684817D01*
X1379599Y685617D01*
X1378999Y686283D01*
X1378199Y686550D01*
G01X1385999Y678550D02*
X1386199Y680283D01*
X1386499Y681750D01*
X1386899Y683083D01*
X1387399Y684550D01*
X1388199Y686550D01*
X1384199D01*
G01X1391999Y679750D02*
X1392599Y679083D01*
X1393299Y678683D01*
X1394199Y678550D01*
X1395099Y678817D01*
X1395799Y679350D01*
X1396299Y680283D01*
X1396399Y681350D01*
X1396199Y682417D01*
X1395699Y683083D01*
X1394999Y683617D01*
X1394299Y683750D01*
X1393599Y683617D01*
X1392699Y683083D01*
X1392999Y686550D01*
X1395699D01*
G01X1400399Y678283D02*
X1403999Y686550D01*
G01X1408899Y681217D02*
X1411499D01*
G01X1418199Y686550D02*
X1417399Y686283D01*
X1416799Y685617D01*
X1416399Y684817D01*
X1416099Y683750D01*
X1415999Y682550D01*
X1416099Y681350D01*
X1416399Y680283D01*
X1416799Y679483D01*
X1417399Y678817D01*
X1418199Y678550D01*
X1418999Y678817D01*
X1419599Y679483D01*
X1419999Y680283D01*
X1420299Y681350D01*
X1420399Y682550D01*
X1420299Y683750D01*
X1419999Y684817D01*
X1419599Y685617D01*
X1418999Y686283D01*
X1418199Y686550D01*
G01X1423199Y678550D02*
Y683883D01*
G01Y682417D02*
X1423499Y683083D01*
X1423999Y683617D01*
X1424699Y683883D01*
X1425399Y683617D01*
X1425899Y683083D01*
X1426199Y682417D01*
Y678550D01*
G01Y682417D02*
X1426499Y683083D01*
X1426999Y683617D01*
X1427699Y683883D01*
X1428399Y683617D01*
X1428899Y683083D01*
X1429199Y682283D01*
Y678550D01*
G01X1431199D02*
Y683883D01*
G01Y682417D02*
X1431499Y683083D01*
X1431999Y683617D01*
X1432699Y683883D01*
X1433399Y683617D01*
X1433899Y683083D01*
X1434199Y682417D01*
Y678550D01*
G01Y682417D02*
X1434499Y683083D01*
X1434999Y683617D01*
X1435699Y683883D01*
X1436399Y683617D01*
X1436899Y683083D01*
X1437199Y682283D01*
Y678550D01*
G01X1369599Y693517D02*
X1371999D01*
G01X1370699Y695250D02*
Y691783D01*
G01X1376899Y690583D02*
X1380499Y698850D01*
G01X1385399Y693517D02*
X1387999D01*
G01X1392799Y697517D02*
X1393399Y698317D01*
X1394099Y698717D01*
X1394899Y698850D01*
X1395899Y698583D01*
X1396599Y697917D01*
X1396799Y697117D01*
X1396699Y696316D01*
X1396299Y695650D01*
X1394299Y694317D01*
X1393399Y693383D01*
X1392799Y692050D01*
X1392599Y690850D01*
X1396799D01*
G01X1399699D02*
Y696183D01*
G01Y694717D02*
X1399999Y695383D01*
X1400499Y695917D01*
X1401199Y696183D01*
X1401899Y695917D01*
X1402399Y695383D01*
X1402699Y694717D01*
Y690850D01*
G01Y694717D02*
X1402999Y695383D01*
X1403499Y695917D01*
X1404199Y696183D01*
X1404899Y695917D01*
X1405399Y695383D01*
X1405699Y694583D01*
Y690850D01*
G01X1410699Y696183D02*
Y690850D01*
G01Y698317D02*
X1410499Y698450D01*
Y698717D01*
X1410699Y698850D01*
X1410899Y698717D01*
Y698450D01*
X1410699Y698317D01*
G01X1418699Y690850D02*
Y698850D01*
G01X1369599Y731517D02*
X1371999D01*
G01X1370699Y733250D02*
Y729783D01*
G01X1376899Y728583D02*
X1380499Y736850D01*
G01X1385399Y731517D02*
X1387999D01*
G01X1392799Y735517D02*
X1393399Y736317D01*
X1394099Y736717D01*
X1394899Y736850D01*
X1395899Y736583D01*
X1396599Y735917D01*
X1396799Y735117D01*
X1396699Y734316D01*
X1396299Y733650D01*
X1394299Y732317D01*
X1393399Y731383D01*
X1392799Y730050D01*
X1392599Y728850D01*
X1396799D01*
G01X1399699D02*
Y734183D01*
G01Y732717D02*
X1399999Y733383D01*
X1400499Y733917D01*
X1401199Y734183D01*
X1401899Y733917D01*
X1402399Y733383D01*
X1402699Y732717D01*
Y728850D01*
G01Y732717D02*
X1402999Y733383D01*
X1403499Y733917D01*
X1404199Y734183D01*
X1404899Y733917D01*
X1405399Y733383D01*
X1405699Y732583D01*
Y728850D01*
G01X1410699Y734183D02*
Y728850D01*
G01Y736317D02*
X1410499Y736450D01*
Y736717D01*
X1410699Y736850D01*
X1410899Y736717D01*
Y736450D01*
X1410699Y736317D01*
G01X1418699Y728850D02*
Y736850D01*
G01X1369599Y714017D02*
X1371999D01*
G01X1370699Y715750D02*
Y712283D01*
G01X1376899Y711083D02*
X1380499Y719350D01*
G01X1385399Y714017D02*
X1387999D01*
G01X1392499Y712950D02*
X1393099Y712017D01*
X1393899Y711483D01*
X1394799Y711350D01*
X1395599Y711483D01*
X1396399Y712150D01*
X1396899Y712950D01*
X1396999Y713750D01*
X1396799Y714683D01*
X1396099Y715350D01*
X1395399Y715617D01*
X1394499D01*
G01X1395399D02*
X1395999Y716017D01*
X1396499Y716683D01*
X1396699Y717483D01*
X1396499Y718283D01*
X1395999Y718950D01*
X1395099Y719350D01*
X1394199Y719217D01*
X1393299Y718683D01*
G01X1399699Y711350D02*
Y716683D01*
G01Y715217D02*
X1399999Y715883D01*
X1400499Y716417D01*
X1401199Y716683D01*
X1401899Y716417D01*
X1402399Y715883D01*
X1402699Y715217D01*
Y711350D01*
G01Y715217D02*
X1402999Y715883D01*
X1403499Y716417D01*
X1404199Y716683D01*
X1404899Y716417D01*
X1405399Y715883D01*
X1405699Y715083D01*
Y711350D01*
G01X1410699Y716683D02*
Y711350D01*
G01Y718817D02*
X1410499Y718950D01*
Y719217D01*
X1410699Y719350D01*
X1410899Y719217D01*
Y718950D01*
X1410699Y718817D01*
G01X1418699Y711350D02*
Y719350D01*
G01X1369599Y757017D02*
X1371999D01*
G01X1370699Y758750D02*
Y755283D01*
G01X1378699Y754350D02*
Y762350D01*
X1377499Y760750D01*
G01Y754350D02*
X1379899D01*
G01X1384899Y754083D02*
X1388499Y762350D01*
G01X1393399Y757017D02*
X1395999D01*
G01X1400499Y755950D02*
X1401099Y755017D01*
X1401899Y754483D01*
X1402799Y754350D01*
X1403599Y754483D01*
X1404399Y755150D01*
X1404899Y755950D01*
X1404999Y756750D01*
X1404799Y757683D01*
X1404099Y758350D01*
X1403399Y758617D01*
X1402499D01*
G01X1403399D02*
X1403999Y759017D01*
X1404499Y759683D01*
X1404699Y760483D01*
X1404499Y761283D01*
X1403999Y761950D01*
X1403099Y762350D01*
X1402199Y762217D01*
X1401299Y761683D01*
G01X1407699Y754350D02*
Y759683D01*
G01Y758217D02*
X1407999Y758883D01*
X1408499Y759417D01*
X1409199Y759683D01*
X1409899Y759417D01*
X1410399Y758883D01*
X1410699Y758217D01*
Y754350D01*
G01Y758217D02*
X1410999Y758883D01*
X1411499Y759417D01*
X1412199Y759683D01*
X1412899Y759417D01*
X1413399Y758883D01*
X1413699Y758083D01*
Y754350D01*
G01X1418699Y759683D02*
Y754350D01*
G01Y761817D02*
X1418499Y761950D01*
Y762217D01*
X1418699Y762350D01*
X1418899Y762217D01*
Y761950D01*
X1418699Y761817D01*
G01X1426699Y754350D02*
Y762350D01*
G01X1369599Y769017D02*
X1371999D01*
G01X1370699Y770750D02*
Y767283D01*
G01X1376799Y773017D02*
X1377399Y773817D01*
X1378099Y774217D01*
X1378899Y774350D01*
X1379899Y774083D01*
X1380599Y773417D01*
X1380799Y772617D01*
X1380699Y771816D01*
X1380299Y771150D01*
X1378299Y769817D01*
X1377399Y768883D01*
X1376799Y767550D01*
X1376599Y766350D01*
X1380799D01*
G01X1384899Y766083D02*
X1388499Y774350D01*
G01X1393399Y769017D02*
X1395999D01*
G01X1403899Y766350D02*
Y774350D01*
X1400199Y768617D01*
X1405199D01*
G01X1407699Y766350D02*
Y771683D01*
G01Y770217D02*
X1407999Y770883D01*
X1408499Y771417D01*
X1409199Y771683D01*
X1409899Y771417D01*
X1410399Y770883D01*
X1410699Y770217D01*
Y766350D01*
G01Y770217D02*
X1410999Y770883D01*
X1411499Y771417D01*
X1412199Y771683D01*
X1412899Y771417D01*
X1413399Y770883D01*
X1413699Y770083D01*
Y766350D01*
G01X1418699Y771683D02*
Y766350D01*
G01Y773817D02*
X1418499Y773950D01*
Y774217D01*
X1418699Y774350D01*
X1418899Y774217D01*
Y773950D01*
X1418699Y773817D01*
G01X1426699Y766350D02*
Y774350D01*
G01X1364699Y802350D02*
Y794350D01*
G01X1362399Y802350D02*
X1366999D01*
G01X1372699Y794350D02*
X1372099Y794483D01*
X1371499Y795017D01*
X1371099Y795950D01*
X1370899Y797017D01*
X1371099Y798083D01*
X1371499Y799017D01*
X1372099Y799550D01*
X1372699Y799683D01*
X1373299Y799550D01*
X1373899Y799017D01*
X1374299Y798083D01*
X1374399Y797017D01*
X1374299Y795950D01*
X1373899Y795017D01*
X1373299Y794483D01*
X1372699Y794350D01*
G01X1380699D02*
Y802350D01*
G01X1387199Y797950D02*
X1390399D01*
X1390099Y798883D01*
X1389599Y799417D01*
X1388899Y799683D01*
X1388199Y799550D01*
X1387599Y799150D01*
X1387199Y798217D01*
X1386999Y797416D01*
Y796617D01*
X1387199Y795817D01*
X1387699Y795017D01*
X1388299Y794483D01*
X1388999Y794350D01*
X1389699Y794617D01*
X1390399Y795416D01*
G01X1395299Y794350D02*
Y799683D01*
G01Y798617D02*
X1395799Y799150D01*
X1396299Y799550D01*
X1396999Y799683D01*
X1397499Y799550D01*
X1398099Y799150D01*
G01X1406499Y794350D02*
Y799683D01*
G01Y798750D02*
X1406099Y799283D01*
X1405499Y799550D01*
X1404799Y799683D01*
X1404099Y799417D01*
X1403499Y798883D01*
X1403099Y798083D01*
X1402899Y797017D01*
X1403099Y795950D01*
X1403499Y795150D01*
X1404099Y794617D01*
X1404799Y794350D01*
X1405499Y794483D01*
X1406099Y794883D01*
X1406499Y795416D01*
G01X1410999Y794350D02*
Y799683D01*
G01Y798350D02*
X1411399Y799017D01*
X1411999Y799550D01*
X1412799Y799683D01*
X1413499Y799550D01*
X1414099Y799017D01*
X1414399Y798083D01*
Y794350D01*
G01X1422299Y799017D02*
X1421599Y799550D01*
X1420999Y799683D01*
X1420199Y799417D01*
X1419599Y798883D01*
X1419199Y797950D01*
X1419099Y797017D01*
X1419199Y796083D01*
X1419599Y795283D01*
X1420199Y794617D01*
X1420999Y794350D01*
X1421699Y794617D01*
X1422299Y795150D01*
G01X1427199Y797950D02*
X1430399D01*
X1430099Y798883D01*
X1429599Y799417D01*
X1428899Y799683D01*
X1428199Y799550D01*
X1427599Y799150D01*
X1427199Y798217D01*
X1426999Y797416D01*
Y796617D01*
X1427199Y795817D01*
X1427699Y795017D01*
X1428299Y794483D01*
X1428999Y794350D01*
X1429699Y794617D01*
X1430399Y795416D01*
G01X1369599Y781517D02*
X1371999D01*
G01X1370699Y783250D02*
Y779783D01*
G01X1376899Y778583D02*
X1380499Y786850D01*
G01X1385399Y781517D02*
X1387999D01*
G01X1392499Y780450D02*
X1393099Y779517D01*
X1393899Y778983D01*
X1394799Y778850D01*
X1395599Y778983D01*
X1396399Y779650D01*
X1396899Y780450D01*
X1396999Y781250D01*
X1396799Y782183D01*
X1396099Y782850D01*
X1395399Y783117D01*
X1394499D01*
G01X1395399D02*
X1395999Y783517D01*
X1396499Y784183D01*
X1396699Y784983D01*
X1396499Y785783D01*
X1395999Y786450D01*
X1395099Y786850D01*
X1394199Y786717D01*
X1393299Y786183D01*
G01X1399699Y778850D02*
Y784183D01*
G01Y782717D02*
X1399999Y783383D01*
X1400499Y783917D01*
X1401199Y784183D01*
X1401899Y783917D01*
X1402399Y783383D01*
X1402699Y782717D01*
Y778850D01*
G01Y782717D02*
X1402999Y783383D01*
X1403499Y783917D01*
X1404199Y784183D01*
X1404899Y783917D01*
X1405399Y783383D01*
X1405699Y782583D01*
Y778850D01*
G01X1410699Y784183D02*
Y778850D01*
G01Y786317D02*
X1410499Y786450D01*
Y786717D01*
X1410699Y786850D01*
X1410899Y786717D01*
Y786450D01*
X1410699Y786317D01*
G01X1418699Y778850D02*
Y786850D01*
G01X131799Y1367750D02*
Y498950D01*
X1672699D01*
Y1367750D01*
X131799D01*
G01Y949350D02*
X1672699D01*
G01X317299Y736150D02*
Y757350D01*
X317199Y757450D01*
X312799Y753050D01*
G01X355299Y757350D02*
X295499D01*
X295399Y757450D01*
G01X318399Y817150D02*
Y797350D01*
X318099Y797050D01*
X315099Y800050D01*
G01X355199Y796850D02*
X295299D01*
G01X313872Y1202147D02*
X313882Y1190147D01*
G01X313872Y1202147D02*
X337893Y1178167D01*
X337899Y1138850D01*
G01X313872Y1202147D02*
X325872Y1202157D01*
G01X330799Y698650D02*
X355399D01*
X355599Y698850D01*
X353199Y701250D01*
G01X317499Y757250D02*
Y757150D01*
X321599Y753050D01*
G01X318299Y796850D02*
X318399D01*
X321499Y799950D01*
G01X318299Y797250D02*
X318699D01*
G01X343299Y671850D02*
X382199D01*
X382499Y672150D01*
X379899Y674750D01*
G01X355399Y698850D02*
Y698550D01*
X353499Y696650D01*
G01X355599Y741250D02*
Y692050D01*
X355499Y691950D01*
G01X355599Y815950D02*
Y887950D01*
G01X355899Y870750D02*
Y870650D01*
X357699Y868850D01*
G01X369399Y870750D02*
X355999D01*
X355799Y870950D01*
X357899Y873050D01*
G01X361699Y698750D02*
Y698550D01*
X364199Y696050D01*
G01X376999Y698650D02*
X361799D01*
X361699Y698750D01*
X364299Y701350D01*
G01X361599Y741450D02*
Y692450D01*
X361499Y692350D01*
G01X371319Y1183320D02*
X413319D01*
G01X371319D02*
X379319Y1175320D01*
G01X371319Y1183320D02*
X379319Y1191320D01*
G01X359779Y1209890D02*
X383779Y1233890D01*
X415779D01*
G01X359779Y1209890D02*
Y1221890D01*
G01Y1209890D02*
X371779D01*
G01X382499Y704250D02*
Y656650D01*
G01X382399Y671850D02*
X382199D01*
X379599Y669250D01*
G01X407499Y704750D02*
Y656750D01*
G01X407599Y672250D02*
Y672150D01*
X410799Y668950D01*
G01X438799Y672150D02*
X407699D01*
X407499Y672350D01*
X410499Y675350D01*
G01X407499Y704250D02*
X501899D01*
X502499Y703650D01*
G01X406499Y850450D02*
X495799D01*
X496299Y850950D01*
G01X413699Y870950D02*
X434599D01*
X434799Y871150D01*
X431999Y873950D01*
X431899D01*
G01X434699Y812850D02*
Y885350D01*
X434799Y885450D01*
G01X434699Y871050D02*
Y870950D01*
X432099Y868350D01*
G01X460499Y704750D02*
X460699D01*
X464299Y708350D01*
G01X460399Y704650D02*
X459899D01*
X455999Y708550D01*
G01X460299Y758550D02*
Y704850D01*
X459699Y704250D01*
G01X459199Y849850D02*
Y798650D01*
X459699Y798150D01*
G01X459199Y850250D02*
X462399Y847050D01*
G01X459099Y850350D02*
X455699Y846950D01*
G01X774999Y1367850D02*
Y498950D01*
G01X798699Y626350D02*
X1451699D01*
Y806350D01*
X798699D01*
Y626350D01*
G01X1451699Y638850D02*
X798699D01*
G01Y663850D02*
Y651350D01*
X826699D01*
Y663850D01*
G01X798699Y676350D02*
Y663850D01*
X826699D01*
Y676350D01*
G01X798699Y688850D02*
Y676350D01*
X826699D01*
Y688850D01*
G01X798699Y701350D02*
Y688850D01*
X826699D01*
Y701350D01*
G01X798699Y713850D02*
Y701350D01*
X826699D01*
Y713850D01*
G01X798699Y738850D02*
Y726350D01*
X826699D01*
Y738850D01*
G01X798699Y763850D02*
Y751350D01*
X826699D01*
Y763850D01*
G01X798699Y776350D02*
Y763850D01*
X826699D01*
Y776350D01*
G01X798699Y788850D02*
Y776350D01*
X826699D01*
Y788850D01*
G01X1451699D02*
X798699D01*
G01X807699Y806350D02*
X1451699D01*
Y788850D01*
X798699D01*
Y806350D01*
X807699D01*
G01X826699Y626350D02*
Y651350D01*
G01Y626350D02*
X940699D01*
Y789350D01*
G01X826199Y766850D02*
X826699D01*
Y710350D01*
G01Y788850D02*
Y806350D01*
G01Y776350D02*
X940699D01*
Y788850D01*
G01X1451699Y651350D02*
X940699D01*
G01X1451699Y663850D02*
X940699D01*
G01Y676350D02*
X1451699D01*
Y688850D01*
G01D02*
X940699D01*
G01X1451699Y701350D02*
X940699D01*
G01X1451699Y726350D02*
X940699D01*
G01X1451699Y763850D02*
X940699D01*
G01X1451699Y751350D02*
X940699D01*
G01Y788850D02*
Y806350D01*
G01X1451699Y776350D02*
X940699D01*
G01X1350199Y626350D02*
Y806350D01*
G01X1360199Y651350D02*
X1451699D01*
Y663850D01*
G01X1360199D02*
X1451699D01*
Y676350D01*
G01X1360199Y688850D02*
X1451699D01*
Y701350D01*
G01X1360199D02*
X1451699D01*
Y726350D01*
G01X1360199D02*
X1451699D01*
Y763850D01*
G01X1360199Y751350D02*
X1451699D01*
Y763850D01*
G01X1360199D02*
X1451699D01*
Y776350D01*
G01X1360199D02*
X1451699D01*
Y788850D01*
G01X1432899Y949350D02*
Y949450D01*
M02*
